(kicad_sch (version 20230121) (generator eeschema)

  (paper "A3")

  (title_block
    (title "Data Center RDIMM DDR4 Tester")
    (date "2024-09-30")
    (rev "1.2.4")
    (company "Antmicro Ltd.")
    (comment 1 "www.antmicro.com")
    (comment 2 "Antmicro Ltd")
  )

  (junction (at 387.985 187.325) (diameter 0) (color 0 0 0 0)
  )
  (junction (at 387.985 196.85) (diameter 0) (color 0 0 0 0)
  )
  (junction (at 210.185 160.02) (diameter 0) (color 0 0 0 0)
  )
  (junction (at 249.555 160.02) (diameter 0) (color 0 0 0 0)
  )
  (junction (at 145.415 147.32) (diameter 0) (color 0 0 0 0)
  )
  (junction (at 143.51 26.67) (diameter 0) (color 0 0 0 0)
  )
  (junction (at 255.905 130.175) (diameter 0) (color 0 0 0 0)
  )
  (junction (at 286.385 160.02) (diameter 0) (color 0 0 0 0)
  )
  (junction (at 40.64 38.1) (diameter 0) (color 0 0 0 0)
  )
  (junction (at 319.405 205.74) (diameter 0) (color 0 0 0 0)
  )
  (junction (at 245.11 245.745) (diameter 0) (color 0 0 0 0)
  )
  (junction (at 207.01 120.015) (diameter 0) (color 0 0 0 0)
  )
  (junction (at 129.54 226.06) (diameter 0) (color 0 0 0 0)
  )
  (junction (at 22.86 113.665) (diameter 0) (color 0 0 0 0)
  )
  (junction (at 137.795 139.7) (diameter 0) (color 0 0 0 0)
  )
  (junction (at 110.49 196.215) (diameter 0) (color 0 0 0 0)
  )
  (junction (at 387.985 136.525) (diameter 0) (color 0 0 0 0)
  )
  (junction (at 52.705 200.66) (diameter 0) (color 0 0 0 0)
  )
  (junction (at 40.64 35.56) (diameter 0) (color 0 0 0 0)
  )
  (junction (at 313.055 180.34) (diameter 0) (color 0 0 0 0)
  )
  (junction (at 314.325 149.86) (diameter 0) (color 0 0 0 0)
  )
  (junction (at 112.395 219.71) (diameter 0) (color 0 0 0 0)
  )
  (junction (at 368.3 36.195) (diameter 0) (color 0 0 0 0)
  )
  (junction (at 86.36 41.91) (diameter 0) (color 0 0 0 0)
  )
  (junction (at 379.095 146.685) (diameter 0) (color 0 0 0 0)
  )
  (junction (at 387.985 127.635) (diameter 0) (color 0 0 0 0)
  )
  (junction (at 38.1 86.995) (diameter 0) (color 0 0 0 0)
  )
  (junction (at 217.805 90.17) (diameter 0) (color 0 0 0 0)
  )
  (junction (at 245.745 120.015) (diameter 0) (color 0 0 0 0)
  )
  (junction (at 283.845 198.12) (diameter 0) (color 0 0 0 0)
  )
  (junction (at 366.395 78.74) (diameter 0) (color 0 0 0 0)
  )
  (junction (at 276.225 198.12) (diameter 0) (color 0 0 0 0)
  )
  (junction (at 387.985 165.1) (diameter 0) (color 0 0 0 0)
  )
  (junction (at 141.605 44.45) (diameter 0) (color 0 0 0 0)
  )
  (junction (at 319.405 198.12) (diameter 0) (color 0 0 0 0)
  )
  (junction (at 379.095 196.85) (diameter 0) (color 0 0 0 0)
  )
  (junction (at 259.715 160.02) (diameter 0) (color 0 0 0 0)
  )
  (junction (at 145.415 139.7) (diameter 0) (color 0 0 0 0)
  )
  (junction (at 208.915 198.12) (diameter 0) (color 0 0 0 0)
  )
  (junction (at 318.135 236.855) (diameter 0) (color 0 0 0 0)
  )
  (junction (at 313.69 129.54) (diameter 0) (color 0 0 0 0)
  )
  (junction (at 140.97 65.405) (diameter 0) (color 0 0 0 0)
  )
  (junction (at 322.58 52.07) (diameter 0) (color 0 0 0 0)
  )
  (junction (at 318.135 241.935) (diameter 0) (color 0 0 0 0)
  )
  (junction (at 134.62 44.45) (diameter 0) (color 0 0 0 0)
  )
  (junction (at 379.095 136.525) (diameter 0) (color 0 0 0 0)
  )
  (junction (at 26.035 200.66) (diameter 0) (color 0 0 0 0)
  )
  (junction (at 83.185 228.6) (diameter 0) (color 0 0 0 0)
  )
  (junction (at 379.095 165.1) (diameter 0) (color 0 0 0 0)
  )
  (junction (at 281.94 120.015) (diameter 0) (color 0 0 0 0)
  )
  (junction (at 125.095 139.7) (diameter 0) (color 0 0 0 0)
  )
  (junction (at 148.59 65.405) (diameter 0) (color 0 0 0 0)
  )
  (junction (at 254 260.35) (diameter 0) (color 0 0 0 0)
  )
  (junction (at 272.415 245.745) (diameter 0) (color 0 0 0 0)
  )
  (junction (at 34.29 113.665) (diameter 0) (color 0 0 0 0)
  )
  (junction (at 320.04 147.32) (diameter 0) (color 0 0 0 0)
  )
  (junction (at 165.735 182.245) (diameter 0) (color 0 0 0 0)
  )
  (junction (at 86.36 26.67) (diameter 0) (color 0 0 0 0)
  )
  (junction (at 103.505 132.08) (diameter 0) (color 0 0 0 0)
  )
  (junction (at 88.9 86.995) (diameter 0) (color 0 0 0 0)
  )
  (junction (at 156.21 192.405) (diameter 0) (color 0 0 0 0)
  )
  (junction (at 316.865 24.765) (diameter 0) (color 0 0 0 0)
  )
  (junction (at 72.39 86.995) (diameter 0) (color 0 0 0 0)
  )
  (junction (at 29.845 86.995) (diameter 0) (color 0 0 0 0)
  )
  (junction (at 314.96 200.66) (diameter 0) (color 0 0 0 0)
  )
  (junction (at 210.693 41.275) (diameter 0) (color 0 0 0 0)
  )
  (junction (at 80.645 86.995) (diameter 0) (color 0 0 0 0)
  )
  (junction (at 210.693 22.225) (diameter 0) (color 0 0 0 0)
  )
  (junction (at 255.905 120.015) (diameter 0) (color 0 0 0 0)
  )
  (junction (at 259.08 208.28) (diameter 0) (color 0 0 0 0)
  )
  (junction (at 132.715 26.67) (diameter 0) (color 0 0 0 0)
  )
  (junction (at 311.15 24.765) (diameter 0) (color 0 0 0 0)
  )
  (junction (at 387.985 146.685) (diameter 0) (color 0 0 0 0)
  )
  (junction (at 112.395 139.7) (diameter 0) (color 0 0 0 0)
  )
  (junction (at 29.845 200.66) (diameter 0) (color 0 0 0 0)
  )
  (junction (at 379.095 206.375) (diameter 0) (color 0 0 0 0)
  )
  (junction (at 259.08 198.12) (diameter 0) (color 0 0 0 0)
  )
  (junction (at 259.715 170.18) (diameter 0) (color 0 0 0 0)
  )
  (junction (at 379.095 127.635) (diameter 0) (color 0 0 0 0)
  )
  (junction (at 243.205 86.36) (diameter 0) (color 0 0 0 0)
  )
  (junction (at 80.645 52.07) (diameter 0) (color 0 0 0 0)
  )
  (junction (at 201.803 51.435) (diameter 0) (color 0 0 0 0)
  )
  (junction (at 387.985 206.375) (diameter 0) (color 0 0 0 0)
  )
  (junction (at 96.52 41.91) (diameter 0) (color 0 0 0 0)
  )
  (junction (at 311.15 41.91) (diameter 0) (color 0 0 0 0)
  )
  (junction (at 316.865 46.99) (diameter 0) (color 0 0 0 0)
  )
  (junction (at 202.438 22.225) (diameter 0) (color 0 0 0 0)
  )
  (junction (at 379.095 187.325) (diameter 0) (color 0 0 0 0)
  )
  (junction (at 387.985 177.8) (diameter 0) (color 0 0 0 0)
  )
  (junction (at 274.32 120.015) (diameter 0) (color 0 0 0 0)
  )
  (junction (at 205.74 245.745) (diameter 0) (color 0 0 0 0)
  )
  (junction (at 156.21 65.405) (diameter 0) (color 0 0 0 0)
  )
  (junction (at 138.43 259.715) (diameter 0) (color 0 0 0 0)
  )
  (junction (at 133.35 65.405) (diameter 0) (color 0 0 0 0)
  )
  (junction (at 278.765 160.02) (diameter 0) (color 0 0 0 0)
  )
  (junction (at 265.43 245.745) (diameter 0) (color 0 0 0 0)
  )
  (junction (at 153.035 139.7) (diameter 0) (color 0 0 0 0)
  )
  (junction (at 379.095 177.8) (diameter 0) (color 0 0 0 0)
  )
  (junction (at 46.355 86.995) (diameter 0) (color 0 0 0 0)
  )
  (junction (at 46.355 142.24) (diameter 0) (color 0 0 0 0)
  )
  (junction (at 109.22 193.675) (diameter 0) (color 0 0 0 0)
  )
  (junction (at 266.7 120.015) (diameter 0) (color 0 0 0 0)
  )
  (junction (at 95.25 151.13) (diameter 0) (color 0 0 0 0)
  )
  (junction (at 394.97 74.93) (diameter 0) (color 0 0 0 0)
  )
  (junction (at 320.04 154.94) (diameter 0) (color 0 0 0 0)
  )
  (junction (at 268.605 198.12) (diameter 0) (color 0 0 0 0)
  )
  (junction (at 125.095 156.21) (diameter 0) (color 0 0 0 0)
  )
  (junction (at 254 245.745) (diameter 0) (color 0 0 0 0)
  )
  (junction (at 248.92 198.12) (diameter 0) (color 0 0 0 0)
  )
  (junction (at 110.49 139.7) (diameter 0) (color 0 0 0 0)
  )
  (junction (at 271.145 160.02) (diameter 0) (color 0 0 0 0)
  )
  (junction (at 279.4 245.745) (diameter 0) (color 0 0 0 0)
  )
  (junction (at 154.305 26.67) (diameter 0) (color 0 0 0 0)
  )
  (junction (at 109.22 196.215) (diameter 0) (color 0 0 0 0)
  )
  (junction (at 394.335 32.385) (diameter 0) (color 0 0 0 0)
  )
  (junction (at 45.085 247.65) (diameter 0) (color 0 0 0 0)
  )

  (no_connect (at 382.27 238.125))

  (wire (pts (xy 93.345 146.05) (xy 108.585 146.05))
    (stroke (width 0) (type default))
  )
  (wire (pts (xy 349.885 99.695) (xy 361.95 99.695))
    (stroke (width 0) (type default))
  )
  (wire (pts (xy 281.94 120.015) (xy 285.115 120.015))
    (stroke (width 0) (type default))
  )
  (wire (pts (xy 387.985 192.405) (xy 400.685 192.405))
    (stroke (width 0) (type default))
  )
  (wire (pts (xy 208.915 198.12) (xy 208.915 205.74))
    (stroke (width 0) (type default))
  )
  (wire (pts (xy 379.095 127.635) (xy 381 127.635))
    (stroke (width 0) (type default))
  )
  (wire (pts (xy 166.37 259.715) (xy 171.45 259.715))
    (stroke (width 0) (type default))
  )
  (wire (pts (xy 125.095 154.94) (xy 125.095 156.21))
    (stroke (width 0) (type default))
  )
  (wire (pts (xy 368.3 37.465) (xy 368.3 36.195))
    (stroke (width 0) (type default))
  )
  (wire (pts (xy 276.225 198.12) (xy 283.845 198.12))
    (stroke (width 0) (type default))
  )
  (wire (pts (xy 386.08 165.1) (xy 387.985 165.1))
    (stroke (width 0) (type default))
  )
  (wire (pts (xy 27.94 86.995) (xy 29.845 86.995))
    (stroke (width 0) (type default))
  )
  (wire (pts (xy 99.06 262.255) (xy 100.965 262.255))
    (stroke (width 0) (type default))
  )
  (wire (pts (xy 379.095 196.85) (xy 381 196.85))
    (stroke (width 0) (type default))
  )
  (wire (pts (xy 387.985 177.8) (xy 391.795 177.8))
    (stroke (width 0) (type default))
  )
  (wire (pts (xy 52.705 200.66) (xy 52.705 201.93))
    (stroke (width 0) (type default))
  )
  (wire (pts (xy 29.845 200.66) (xy 26.035 200.66))
    (stroke (width 0) (type default))
  )
  (wire (pts (xy 366.395 78.74) (xy 370.205 78.74))
    (stroke (width 0) (type default))
  )
  (wire (pts (xy 103.505 128.27) (xy 103.505 132.08))
    (stroke (width 0) (type default))
  )
  (wire (pts (xy 112.395 139.7) (xy 115.57 139.7))
    (stroke (width 0) (type default))
  )
  (wire (pts (xy 346.71 132.08) (xy 360.045 132.08))
    (stroke (width 0) (type default))
  )
  (wire (pts (xy 374.015 206.375) (xy 379.095 206.375))
    (stroke (width 0) (type default))
  )
  (wire (pts (xy 316.865 36.195) (xy 316.865 46.99))
    (stroke (width 0) (type default))
  )
  (wire (pts (xy 210.185 160.02) (xy 210.185 167.64))
    (stroke (width 0) (type default))
  )
  (wire (pts (xy 387.985 206.375) (xy 387.985 207.01))
    (stroke (width 0) (type default))
  )
  (wire (pts (xy 285.115 49.53) (xy 290.83 49.53))
    (stroke (width 0) (type default))
  )
  (wire (pts (xy 265.43 245.745) (xy 265.43 252.095))
    (stroke (width 0) (type default))
  )
  (wire (pts (xy 89.535 191.135) (xy 97.155 191.135))
    (stroke (width 0) (type default))
  )
  (wire (pts (xy 41.91 38.1) (xy 40.64 38.1))
    (stroke (width 0) (type default))
  )
  (wire (pts (xy 359.41 28.575) (xy 370.205 28.575))
    (stroke (width 0) (type default))
  )
  (wire (pts (xy 394.97 93.98) (xy 394.97 95.25))
    (stroke (width 0) (type default))
  )
  (wire (pts (xy 366.395 78.74) (xy 366.395 80.01))
    (stroke (width 0) (type default))
  )
  (wire (pts (xy 156.21 193.675) (xy 156.21 192.405))
    (stroke (width 0) (type default))
  )
  (wire (pts (xy 66.04 227.33) (xy 66.04 228.6))
    (stroke (width 0) (type default))
  )
  (wire (pts (xy 48.26 207.01) (xy 48.26 205.74))
    (stroke (width 0) (type default))
  )
  (wire (pts (xy 278.765 160.02) (xy 278.765 166.37))
    (stroke (width 0) (type default))
  )
  (wire (pts (xy 238.125 90.17) (xy 239.395 90.17))
    (stroke (width 0) (type default))
  )
  (wire (pts (xy 346.71 180.34) (xy 360.045 180.34))
    (stroke (width 0) (type default))
  )
  (wire (pts (xy 215.265 250.825) (xy 217.17 250.825))
    (stroke (width 0) (type default))
  )
  (wire (pts (xy 83.185 228.6) (xy 81.28 228.6))
    (stroke (width 0) (type default))
  )
  (wire (pts (xy 346.71 182.88) (xy 360.045 182.88))
    (stroke (width 0) (type default))
  )
  (wire (pts (xy 241.935 198.12) (xy 248.92 198.12))
    (stroke (width 0) (type default))
  )
  (wire (pts (xy 255.905 130.175) (xy 255.905 128.27))
    (stroke (width 0) (type default))
  )
  (wire (pts (xy 255.905 132.08) (xy 255.905 130.175))
    (stroke (width 0) (type default))
  )
  (wire (pts (xy 314.325 149.86) (xy 314.325 152.4))
    (stroke (width 0) (type default))
  )
  (wire (pts (xy 318.135 241.935) (xy 318.135 245.745))
    (stroke (width 0) (type default))
  )
  (wire (pts (xy 314.96 200.66) (xy 314.96 202.565))
    (stroke (width 0) (type default))
  )
  (wire (pts (xy 122.555 188.595) (xy 125.73 188.595))
    (stroke (width 0) (type default))
  )
  (wire (pts (xy 322.58 36.195) (xy 322.58 52.07))
    (stroke (width 0) (type default))
  )
  (wire (pts (xy 109.22 193.675) (xy 109.22 191.135))
    (stroke (width 0) (type default))
  )
  (wire (pts (xy 379.095 187.325) (xy 379.095 187.96))
    (stroke (width 0) (type default))
  )
  (wire (pts (xy 46.355 86.995) (xy 38.1 86.995))
    (stroke (width 0) (type default))
  )
  (wire (pts (xy 20.32 113.665) (xy 22.86 113.665))
    (stroke (width 0) (type default))
  )
  (wire (pts (xy 138.43 253.365) (xy 139.7 253.365))
    (stroke (width 0) (type default))
  )
  (wire (pts (xy 323.85 85.09) (xy 322.58 85.09))
    (stroke (width 0) (type default))
  )
  (wire (pts (xy 66.04 26.67) (xy 73.66 26.67))
    (stroke (width 0) (type default))
  )
  (wire (pts (xy 245.745 125.095) (xy 244.475 125.095))
    (stroke (width 0) (type default))
  )
  (wire (pts (xy 205.74 255.905) (xy 205.74 245.745))
    (stroke (width 0) (type default))
  )
  (wire (pts (xy 157.48 262.255) (xy 157.48 263.525))
    (stroke (width 0) (type default))
  )
  (wire (pts (xy 191.135 85.725) (xy 192.405 85.725))
    (stroke (width 0) (type default))
  )
  (wire (pts (xy 143.51 192.405) (xy 156.21 192.405))
    (stroke (width 0) (type default))
  )
  (wire (pts (xy 321.31 154.94) (xy 320.04 154.94))
    (stroke (width 0) (type default))
  )
  (polyline (pts (xy 12.7 238.76) (xy 187.96 238.76))
    (stroke (width 0) (type default))
  )

  (wire (pts (xy 146.685 83.82) (xy 146.685 86.36))
    (stroke (width 0) (type default))
  )
  (wire (pts (xy 272.415 245.745) (xy 279.4 245.745))
    (stroke (width 0) (type default))
  )
  (wire (pts (xy 31.115 200.66) (xy 29.845 200.66))
    (stroke (width 0) (type default))
  )
  (wire (pts (xy 349.25 55.245) (xy 363.22 55.245))
    (stroke (width 0) (type default))
  )
  (wire (pts (xy 86.36 26.67) (xy 99.06 26.67))
    (stroke (width 0) (type default))
  )
  (wire (pts (xy 213.995 203.2) (xy 193.04 203.2))
    (stroke (width 0) (type default))
  )
  (wire (pts (xy 110.49 196.215) (xy 109.22 196.215))
    (stroke (width 0) (type default))
  )
  (wire (pts (xy 26.035 200.66) (xy 26.035 203.2))
    (stroke (width 0) (type default))
  )
  (wire (pts (xy 308.61 52.07) (xy 322.58 52.07))
    (stroke (width 0) (type default))
  )
  (wire (pts (xy 125.095 156.21) (xy 125.095 157.48))
    (stroke (width 0) (type default))
  )
  (wire (pts (xy 386.08 196.85) (xy 387.985 196.85))
    (stroke (width 0) (type default))
  )
  (wire (pts (xy 34.29 113.665) (xy 45.72 113.665))
    (stroke (width 0) (type default))
  )
  (wire (pts (xy 368.3 55.245) (xy 377.825 55.245))
    (stroke (width 0) (type default))
  )
  (wire (pts (xy 80.645 52.07) (xy 80.645 54.61))
    (stroke (width 0) (type default))
  )
  (wire (pts (xy 387.985 140.97) (xy 387.985 141.605))
    (stroke (width 0) (type default))
  )
  (wire (pts (xy 319.405 195.58) (xy 319.405 198.12))
    (stroke (width 0) (type default))
  )
  (wire (pts (xy 320.04 132.08) (xy 321.31 132.08))
    (stroke (width 0) (type default))
  )
  (wire (pts (xy 213.995 165.1) (xy 191.77 165.1))
    (stroke (width 0) (type default))
  )
  (wire (pts (xy 141.605 44.45) (xy 141.605 47.625))
    (stroke (width 0) (type default))
  )
  (wire (pts (xy 143.51 26.67) (xy 154.305 26.67))
    (stroke (width 0) (type default))
  )
  (wire (pts (xy 259.715 170.18) (xy 259.715 171.45))
    (stroke (width 0) (type default))
  )
  (wire (pts (xy 320.04 144.78) (xy 320.04 147.32))
    (stroke (width 0) (type default))
  )
  (wire (pts (xy 361.315 152.4) (xy 346.71 152.4))
    (stroke (width 0) (type default))
  )
  (wire (pts (xy 163.83 65.405) (xy 156.21 65.405))
    (stroke (width 0) (type default))
  )
  (wire (pts (xy 346.71 203.2) (xy 360.045 203.2))
    (stroke (width 0) (type default))
  )
  (wire (pts (xy 231.775 71.12) (xy 245.745 71.12))
    (stroke (width 0) (type default))
  )
  (wire (pts (xy 242.57 170.18) (xy 259.715 170.18))
    (stroke (width 0) (type default))
  )
  (wire (pts (xy 40.64 38.1) (xy 40.64 49.53))
    (stroke (width 0) (type default))
  )
  (wire (pts (xy 128.27 26.67) (xy 132.715 26.67))
    (stroke (width 0) (type default))
  )
  (wire (pts (xy 245.745 120.015) (xy 248.285 120.015))
    (stroke (width 0) (type default))
  )
  (wire (pts (xy 387.985 132.08) (xy 387.985 132.715))
    (stroke (width 0) (type default))
  )
  (wire (pts (xy 145.415 140.97) (xy 145.415 139.7))
    (stroke (width 0) (type default))
  )
  (wire (pts (xy 387.985 187.325) (xy 387.985 187.96))
    (stroke (width 0) (type default))
  )
  (wire (pts (xy 228.6 45.72) (xy 228.6 43.815))
    (stroke (width 0) (type default))
  )
  (wire (pts (xy 201.803 51.435) (xy 201.803 52.705))
    (stroke (width 0) (type default))
  )
  (wire (pts (xy 96.52 44.45) (xy 96.52 41.91))
    (stroke (width 0) (type default))
  )
  (wire (pts (xy 274.32 41.91) (xy 290.83 41.91))
    (stroke (width 0) (type default))
  )
  (wire (pts (xy 93.345 139.7) (xy 110.49 139.7))
    (stroke (width 0) (type default))
  )
  (wire (pts (xy 210.185 160.02) (xy 222.25 160.02))
    (stroke (width 0) (type default))
  )
  (wire (pts (xy 379.095 201.93) (xy 365.76 201.93))
    (stroke (width 0) (type default))
  )
  (wire (pts (xy 201.803 51.435) (xy 203.073 51.435))
    (stroke (width 0) (type default))
  )
  (wire (pts (xy 165.1 26.67) (xy 165.1 28.575))
    (stroke (width 0) (type default))
  )
  (wire (pts (xy 346.71 190.5) (xy 360.045 190.5))
    (stroke (width 0) (type default))
  )
  (wire (pts (xy 379.095 169.545) (xy 379.095 170.18))
    (stroke (width 0) (type default))
  )
  (wire (pts (xy 379.095 201.295) (xy 379.095 201.93))
    (stroke (width 0) (type default))
  )
  (wire (pts (xy 137.795 139.7) (xy 145.415 139.7))
    (stroke (width 0) (type default))
  )
  (wire (pts (xy 148.59 65.405) (xy 140.97 65.405))
    (stroke (width 0) (type default))
  )
  (wire (pts (xy 215.9 125.095) (xy 218.44 125.095))
    (stroke (width 0) (type default))
  )
  (wire (pts (xy 367.03 99.695) (xy 377.19 99.695))
    (stroke (width 0) (type default))
  )
  (wire (pts (xy 268.605 198.12) (xy 276.225 198.12))
    (stroke (width 0) (type default))
  )
  (wire (pts (xy 379.095 210.82) (xy 379.095 211.455))
    (stroke (width 0) (type default))
  )
  (wire (pts (xy 165.735 182.245) (xy 165.735 183.515))
    (stroke (width 0) (type default))
  )
  (wire (pts (xy 249.555 160.02) (xy 252.095 160.02))
    (stroke (width 0) (type default))
  )
  (wire (pts (xy 379.095 192.405) (xy 365.76 192.405))
    (stroke (width 0) (type default))
  )
  (wire (pts (xy 245.745 120.015) (xy 245.745 125.095))
    (stroke (width 0) (type default))
  )
  (wire (pts (xy 103.505 123.19) (xy 103.505 121.285))
    (stroke (width 0) (type default))
  )
  (wire (pts (xy 346.71 195.58) (xy 360.045 195.58))
    (stroke (width 0) (type default))
  )
  (wire (pts (xy 68.58 256.54) (xy 81.28 256.54))
    (stroke (width 0) (type default))
  )
  (wire (pts (xy 144.78 213.36) (xy 147.955 213.36))
    (stroke (width 0) (type default))
  )
  (wire (pts (xy 379.095 177.8) (xy 381 177.8))
    (stroke (width 0) (type default))
  )
  (wire (pts (xy 109.22 193.675) (xy 109.22 196.215))
    (stroke (width 0) (type default))
  )
  (wire (pts (xy 245.11 245.745) (xy 247.015 245.745))
    (stroke (width 0) (type default))
  )
  (wire (pts (xy 157.48 262.255) (xy 156.21 262.255))
    (stroke (width 0) (type default))
  )
  (wire (pts (xy 316.23 241.935) (xy 318.135 241.935))
    (stroke (width 0) (type default))
  )
  (wire (pts (xy 219.583 22.225) (xy 219.583 24.13))
    (stroke (width 0) (type default))
  )
  (wire (pts (xy 259.08 206.375) (xy 259.08 208.28))
    (stroke (width 0) (type default))
  )
  (wire (pts (xy 166.37 253.365) (xy 171.45 253.365))
    (stroke (width 0) (type default))
  )
  (wire (pts (xy 210.693 41.275) (xy 210.693 42.545))
    (stroke (width 0) (type default))
  )
  (wire (pts (xy 362.585 71.12) (xy 370.205 71.12))
    (stroke (width 0) (type default))
  )
  (wire (pts (xy 208.915 198.12) (xy 221.615 198.12))
    (stroke (width 0) (type default))
  )
  (wire (pts (xy 100.965 262.255) (xy 100.965 263.525))
    (stroke (width 0) (type default))
  )
  (wire (pts (xy 217.805 90.17) (xy 220.345 90.17))
    (stroke (width 0) (type default))
  )
  (wire (pts (xy 120.65 139.7) (xy 125.095 139.7))
    (stroke (width 0) (type default))
  )
  (wire (pts (xy 219.075 203.2) (xy 221.615 203.2))
    (stroke (width 0) (type default))
  )
  (wire (pts (xy 40.64 54.61) (xy 40.64 58.42))
    (stroke (width 0) (type default))
  )
  (wire (pts (xy 129.54 223.52) (xy 129.54 226.06))
    (stroke (width 0) (type default))
  )
  (wire (pts (xy 46.355 142.24) (xy 60.325 142.24))
    (stroke (width 0) (type default))
  )
  (wire (pts (xy 314.96 132.08) (xy 313.69 132.08))
    (stroke (width 0) (type default))
  )
  (wire (pts (xy 226.06 38.735) (xy 229.87 38.735))
    (stroke (width 0) (type default))
  )
  (wire (pts (xy 76.2 228.6) (xy 66.04 228.6))
    (stroke (width 0) (type default))
  )
  (wire (pts (xy 279.4 245.745) (xy 286.385 245.745))
    (stroke (width 0) (type default))
  )
  (wire (pts (xy 102.235 196.215) (xy 109.22 196.215))
    (stroke (width 0) (type default))
  )
  (wire (pts (xy 286.385 166.37) (xy 286.385 160.02))
    (stroke (width 0) (type default))
  )
  (polyline (pts (xy 363.22 108.585) (xy 363.22 252.73))
    (stroke (width 0) (type default))
  )

  (wire (pts (xy 217.17 210.82) (xy 217.17 208.28))
    (stroke (width 0) (type default))
  )
  (wire (pts (xy 313.055 180.34) (xy 321.31 180.34))
    (stroke (width 0) (type default))
  )
  (wire (pts (xy 280.035 24.765) (xy 280.035 26.67))
    (stroke (width 0) (type default))
  )
  (polyline (pts (xy 187.96 148.59) (xy 299.72 148.59))
    (stroke (width 0) (type default))
  )

  (wire (pts (xy 210.693 22.225) (xy 210.693 24.13))
    (stroke (width 0) (type default))
  )
  (wire (pts (xy 241.935 203.2) (xy 242.57 203.2))
    (stroke (width 0) (type default))
  )
  (wire (pts (xy 382.27 235.585) (xy 387.35 235.585))
    (stroke (width 0) (type default))
  )
  (wire (pts (xy 387.985 187.325) (xy 391.795 187.325))
    (stroke (width 0) (type default))
  )
  (wire (pts (xy 163.83 182.245) (xy 165.735 182.245))
    (stroke (width 0) (type default))
  )
  (wire (pts (xy 65.405 142.24) (xy 67.945 142.24))
    (stroke (width 0) (type default))
  )
  (wire (pts (xy 379.095 146.685) (xy 379.095 147.32))
    (stroke (width 0) (type default))
  )
  (wire (pts (xy 66.04 69.85) (xy 67.945 69.85))
    (stroke (width 0) (type default))
  )
  (wire (pts (xy 205.74 245.745) (xy 217.17 245.745))
    (stroke (width 0) (type default))
  )
  (wire (pts (xy 216.535 130.175) (xy 216.535 134.62))
    (stroke (width 0) (type default))
  )
  (wire (pts (xy 156.21 253.365) (xy 161.29 253.365))
    (stroke (width 0) (type default))
  )
  (wire (pts (xy 40.005 69.85) (xy 40.005 72.39))
    (stroke (width 0) (type default))
  )
  (wire (pts (xy 379.095 206.375) (xy 379.095 207.01))
    (stroke (width 0) (type default))
  )
  (wire (pts (xy 389.89 78.74) (xy 387.985 78.74))
    (stroke (width 0) (type default))
  )
  (wire (pts (xy 133.35 65.405) (xy 133.35 67.945))
    (stroke (width 0) (type default))
  )
  (wire (pts (xy 112.395 219.71) (xy 116.84 219.71))
    (stroke (width 0) (type default))
  )
  (wire (pts (xy 379.095 146.685) (xy 381 146.685))
    (stroke (width 0) (type default))
  )
  (wire (pts (xy 311.15 139.7) (xy 321.31 139.7))
    (stroke (width 0) (type default))
  )
  (wire (pts (xy 274.32 46.99) (xy 290.83 46.99))
    (stroke (width 0) (type default))
  )
  (wire (pts (xy 217.805 90.17) (xy 217.805 91.44))
    (stroke (width 0) (type default))
  )
  (wire (pts (xy 54.61 89.535) (xy 54.61 86.995))
    (stroke (width 0) (type default))
  )
  (wire (pts (xy 154.305 26.67) (xy 165.1 26.67))
    (stroke (width 0) (type default))
  )
  (wire (pts (xy 379.095 177.8) (xy 379.095 178.435))
    (stroke (width 0) (type default))
  )
  (wire (pts (xy 50.165 247.65) (xy 50.165 250.19))
    (stroke (width 0) (type default))
  )
  (polyline (pts (xy 187.96 228.6) (xy 299.72 228.6))
    (stroke (width 0) (type default))
  )

  (wire (pts (xy 394.97 74.93) (xy 403.86 74.93))
    (stroke (width 0) (type default))
  )
  (wire (pts (xy 238.125 86.36) (xy 243.205 86.36))
    (stroke (width 0) (type default))
  )
  (polyline (pts (xy 345.44 12.7) (xy 345.44 74.93))
    (stroke (width 0) (type default))
  )

  (wire (pts (xy 132.715 26.67) (xy 132.715 28.575))
    (stroke (width 0) (type default))
  )
  (wire (pts (xy 387.985 210.82) (xy 387.985 211.455))
    (stroke (width 0) (type default))
  )
  (wire (pts (xy 353.695 231.14) (xy 356.87 231.14))
    (stroke (width 0) (type default))
  )
  (wire (pts (xy 22.86 113.665) (xy 22.86 116.205))
    (stroke (width 0) (type default))
  )
  (wire (pts (xy 387.985 132.715) (xy 403.86 132.715))
    (stroke (width 0) (type default))
  )
  (wire (pts (xy 346.71 139.7) (xy 360.045 139.7))
    (stroke (width 0) (type default))
  )
  (wire (pts (xy 241.935 208.28) (xy 259.08 208.28))
    (stroke (width 0) (type default))
  )
  (wire (pts (xy 149.86 220.98) (xy 144.78 220.98))
    (stroke (width 0) (type default))
  )
  (wire (pts (xy 106.045 134.62) (xy 110.49 134.62))
    (stroke (width 0) (type default))
  )
  (wire (pts (xy 46.355 86.995) (xy 46.355 89.535))
    (stroke (width 0) (type default))
  )
  (wire (pts (xy 248.92 203.2) (xy 248.92 198.12))
    (stroke (width 0) (type default))
  )
  (wire (pts (xy 219.075 172.72) (xy 219.075 170.18))
    (stroke (width 0) (type default))
  )
  (wire (pts (xy 46.355 139.7) (xy 46.355 142.24))
    (stroke (width 0) (type default))
  )
  (wire (pts (xy 237.49 245.745) (xy 245.11 245.745))
    (stroke (width 0) (type default))
  )
  (wire (pts (xy 257.175 160.02) (xy 259.715 160.02))
    (stroke (width 0) (type default))
  )
  (wire (pts (xy 286.385 160.02) (xy 287.655 160.02))
    (stroke (width 0) (type default))
  )
  (wire (pts (xy 66.04 44.45) (xy 96.52 44.45))
    (stroke (width 0) (type default))
  )
  (wire (pts (xy 278.765 160.02) (xy 286.385 160.02))
    (stroke (width 0) (type default))
  )
  (wire (pts (xy 238.76 120.015) (xy 245.745 120.015))
    (stroke (width 0) (type default))
  )
  (wire (pts (xy 141.605 44.45) (xy 148.59 44.45))
    (stroke (width 0) (type default))
  )
  (wire (pts (xy 245.11 250.825) (xy 245.11 245.745))
    (stroke (width 0) (type default))
  )
  (wire (pts (xy 387.985 146.685) (xy 396.24 146.685))
    (stroke (width 0) (type default))
  )
  (wire (pts (xy 31.115 203.2) (xy 29.845 203.2))
    (stroke (width 0) (type default))
  )
  (wire (pts (xy 78.74 26.67) (xy 86.36 26.67))
    (stroke (width 0) (type default))
  )
  (wire (pts (xy 363.855 36.195) (xy 368.3 36.195))
    (stroke (width 0) (type default))
  )
  (wire (pts (xy 379.095 191.77) (xy 379.095 192.405))
    (stroke (width 0) (type default))
  )
  (wire (pts (xy 374.015 187.325) (xy 379.095 187.325))
    (stroke (width 0) (type default))
  )
  (wire (pts (xy 67.945 69.85) (xy 67.945 72.39))
    (stroke (width 0) (type default))
  )
  (wire (pts (xy 314.325 149.86) (xy 321.31 149.86))
    (stroke (width 0) (type default))
  )
  (wire (pts (xy 99.695 151.13) (xy 95.25 151.13))
    (stroke (width 0) (type default))
  )
  (wire (pts (xy 143.51 26.67) (xy 143.51 28.575))
    (stroke (width 0) (type default))
  )
  (wire (pts (xy 110.49 134.62) (xy 110.49 139.7))
    (stroke (width 0) (type default))
  )
  (wire (pts (xy 387.985 146.685) (xy 387.985 147.32))
    (stroke (width 0) (type default))
  )
  (wire (pts (xy 55.88 132.08) (xy 67.945 132.08))
    (stroke (width 0) (type default))
  )
  (wire (pts (xy 346.71 147.32) (xy 360.045 147.32))
    (stroke (width 0) (type default))
  )
  (wire (pts (xy 201.93 90.17) (xy 217.805 90.17))
    (stroke (width 0) (type default))
  )
  (wire (pts (xy 373.38 136.525) (xy 379.095 136.525))
    (stroke (width 0) (type default))
  )
  (wire (pts (xy 40.64 35.56) (xy 41.91 35.56))
    (stroke (width 0) (type default))
  )
  (wire (pts (xy 323.85 97.79) (xy 322.58 97.79))
    (stroke (width 0) (type default))
  )
  (wire (pts (xy 387.985 182.88) (xy 400.685 182.88))
    (stroke (width 0) (type default))
  )
  (wire (pts (xy 387.985 141.605) (xy 403.86 141.605))
    (stroke (width 0) (type default))
  )
  (wire (pts (xy 40.64 38.1) (xy 40.64 35.56))
    (stroke (width 0) (type default))
  )
  (wire (pts (xy 167.64 218.44) (xy 173.99 218.44))
    (stroke (width 0) (type default))
  )
  (wire (pts (xy 316.23 239.395) (xy 318.135 239.395))
    (stroke (width 0) (type default))
  )
  (wire (pts (xy 314.96 182.88) (xy 313.055 182.88))
    (stroke (width 0) (type default))
  )
  (wire (pts (xy 279.4 252.095) (xy 279.4 245.745))
    (stroke (width 0) (type default))
  )
  (wire (pts (xy 46.355 205.74) (xy 48.26 205.74))
    (stroke (width 0) (type default))
  )
  (wire (pts (xy 346.71 129.54) (xy 360.045 129.54))
    (stroke (width 0) (type default))
  )
  (wire (pts (xy 389.255 42.545) (xy 389.255 36.195))
    (stroke (width 0) (type default))
  )
  (wire (pts (xy 274.32 120.015) (xy 274.32 126.365))
    (stroke (width 0) (type default))
  )
  (wire (pts (xy 379.095 151.13) (xy 379.095 151.765))
    (stroke (width 0) (type default))
  )
  (polyline (pts (xy 299.72 220.345) (xy 407.67 220.345))
    (stroke (width 0) (type default))
  )

  (wire (pts (xy 283.845 198.12) (xy 286.385 198.12))
    (stroke (width 0) (type default))
  )
  (wire (pts (xy 243.205 86.36) (xy 257.175 86.36))
    (stroke (width 0) (type default))
  )
  (wire (pts (xy 145.415 139.7) (xy 153.035 139.7))
    (stroke (width 0) (type default))
  )
  (wire (pts (xy 29.845 26.67) (xy 41.91 26.67))
    (stroke (width 0) (type default))
  )
  (wire (pts (xy 248.285 260.35) (xy 248.285 255.905))
    (stroke (width 0) (type default))
  )
  (wire (pts (xy 387.985 191.77) (xy 387.985 192.405))
    (stroke (width 0) (type default))
  )
  (wire (pts (xy 254 247.65) (xy 254 245.745))
    (stroke (width 0) (type default))
  )
  (wire (pts (xy 97.155 196.215) (xy 89.535 196.215))
    (stroke (width 0) (type default))
  )
  (wire (pts (xy 140.97 65.405) (xy 140.97 67.945))
    (stroke (width 0) (type default))
  )
  (wire (pts (xy 259.715 168.275) (xy 259.715 170.18))
    (stroke (width 0) (type default))
  )
  (wire (pts (xy 274.32 53.34) (xy 274.32 46.99))
    (stroke (width 0) (type default))
  )
  (wire (pts (xy 148.59 44.45) (xy 148.59 47.625))
    (stroke (width 0) (type default))
  )
  (wire (pts (xy 191.77 125.095) (xy 210.82 125.095))
    (stroke (width 0) (type default))
  )
  (wire (pts (xy 167.64 223.52) (xy 168.91 223.52))
    (stroke (width 0) (type default))
  )
  (wire (pts (xy 154.305 26.67) (xy 154.305 28.575))
    (stroke (width 0) (type default))
  )
  (wire (pts (xy 163.83 44.45) (xy 160.655 44.45))
    (stroke (width 0) (type default))
  )
  (wire (pts (xy 313.055 182.88) (xy 313.055 180.34))
    (stroke (width 0) (type default))
  )
  (wire (pts (xy 387.985 170.18) (xy 403.225 170.18))
    (stroke (width 0) (type default))
  )
  (wire (pts (xy 243.205 165.1) (xy 242.57 165.1))
    (stroke (width 0) (type default))
  )
  (wire (pts (xy 156.21 182.245) (xy 158.75 182.245))
    (stroke (width 0) (type default))
  )
  (wire (pts (xy 66.04 36.83) (xy 70.485 36.83))
    (stroke (width 0) (type default))
  )
  (wire (pts (xy 387.985 201.93) (xy 400.685 201.93))
    (stroke (width 0) (type default))
  )
  (wire (pts (xy 394.335 32.385) (xy 394.335 37.465))
    (stroke (width 0) (type default))
  )
  (wire (pts (xy 41.91 69.85) (xy 40.005 69.85))
    (stroke (width 0) (type default))
  )
  (wire (pts (xy 52.705 200.66) (xy 57.15 200.66))
    (stroke (width 0) (type default))
  )
  (wire (pts (xy 29.845 35.56) (xy 40.64 35.56))
    (stroke (width 0) (type default))
  )
  (wire (pts (xy 346.71 137.16) (xy 360.045 137.16))
    (stroke (width 0) (type default))
  )
  (wire (pts (xy 75.565 54.61) (xy 80.645 54.61))
    (stroke (width 0) (type default))
  )
  (polyline (pts (xy 299.72 109.22) (xy 299.72 252.73))
    (stroke (width 0) (type default))
  )

  (wire (pts (xy 34.29 113.665) (xy 34.29 116.205))
    (stroke (width 0) (type default))
  )
  (wire (pts (xy 202.438 22.225) (xy 202.438 24.13))
    (stroke (width 0) (type default))
  )
  (wire (pts (xy 127 259.715) (xy 138.43 259.715))
    (stroke (width 0) (type default))
  )
  (wire (pts (xy 289.56 54.61) (xy 290.83 54.61))
    (stroke (width 0) (type default))
  )
  (wire (pts (xy 328.295 233.045) (xy 327.025 233.045))
    (stroke (width 0) (type default))
  )
  (wire (pts (xy 201.295 245.745) (xy 205.74 245.745))
    (stroke (width 0) (type default))
  )
  (wire (pts (xy 156.21 192.405) (xy 158.115 192.405))
    (stroke (width 0) (type default))
  )
  (wire (pts (xy 45.72 113.665) (xy 45.72 116.205))
    (stroke (width 0) (type default))
  )
  (wire (pts (xy 272.415 245.745) (xy 272.415 252.095))
    (stroke (width 0) (type default))
  )
  (wire (pts (xy 379.095 136.525) (xy 381 136.525))
    (stroke (width 0) (type default))
  )
  (wire (pts (xy 281.94 120.015) (xy 281.94 126.365))
    (stroke (width 0) (type default))
  )
  (wire (pts (xy 108.585 219.71) (xy 112.395 219.71))
    (stroke (width 0) (type default))
  )
  (wire (pts (xy 210.693 22.225) (xy 219.583 22.225))
    (stroke (width 0) (type default))
  )
  (wire (pts (xy 387.985 136.525) (xy 397.51 136.525))
    (stroke (width 0) (type default))
  )
  (wire (pts (xy 38.1 86.995) (xy 38.1 89.535))
    (stroke (width 0) (type default))
  )
  (wire (pts (xy 22.86 200.66) (xy 26.035 200.66))
    (stroke (width 0) (type default))
  )
  (wire (pts (xy 379.095 182.245) (xy 379.095 182.88))
    (stroke (width 0) (type default))
  )
  (wire (pts (xy 379.095 137.16) (xy 379.095 136.525))
    (stroke (width 0) (type default))
  )
  (polyline (pts (xy 187.96 186.69) (xy 299.72 186.69))
    (stroke (width 0) (type default))
  )

  (wire (pts (xy 379.095 165.1) (xy 379.095 165.735))
    (stroke (width 0) (type default))
  )
  (wire (pts (xy 109.22 191.135) (xy 102.235 191.135))
    (stroke (width 0) (type default))
  )
  (wire (pts (xy 86.36 29.21) (xy 86.36 26.67))
    (stroke (width 0) (type default))
  )
  (wire (pts (xy 346.71 144.78) (xy 360.045 144.78))
    (stroke (width 0) (type default))
  )
  (wire (pts (xy 387.985 32.385) (xy 394.335 32.385))
    (stroke (width 0) (type default))
  )
  (wire (pts (xy 145.415 147.32) (xy 145.415 148.59))
    (stroke (width 0) (type default))
  )
  (wire (pts (xy 374.015 177.8) (xy 379.095 177.8))
    (stroke (width 0) (type default))
  )
  (wire (pts (xy 356.87 231.14) (xy 356.87 233.045))
    (stroke (width 0) (type default))
  )
  (wire (pts (xy 394.97 74.93) (xy 394.97 80.01))
    (stroke (width 0) (type default))
  )
  (wire (pts (xy 386.08 177.8) (xy 387.985 177.8))
    (stroke (width 0) (type default))
  )
  (wire (pts (xy 102.235 193.675) (xy 109.22 193.675))
    (stroke (width 0) (type default))
  )
  (wire (pts (xy 29.21 63.5) (xy 41.91 63.5))
    (stroke (width 0) (type default))
  )
  (wire (pts (xy 203.2 198.12) (xy 208.915 198.12))
    (stroke (width 0) (type default))
  )
  (wire (pts (xy 255.905 123.19) (xy 255.905 120.015))
    (stroke (width 0) (type default))
  )
  (wire (pts (xy 387.985 165.1) (xy 387.985 165.735))
    (stroke (width 0) (type default))
  )
  (wire (pts (xy 316.865 24.765) (xy 311.15 24.765))
    (stroke (width 0) (type default))
  )
  (wire (pts (xy 86.36 41.91) (xy 86.36 36.83))
    (stroke (width 0) (type default))
  )
  (wire (pts (xy 207.01 129.54) (xy 207.01 120.015))
    (stroke (width 0) (type default))
  )
  (wire (pts (xy 89.535 196.215) (xy 89.535 197.485))
    (stroke (width 0) (type default))
  )
  (wire (pts (xy 368.3 36.195) (xy 370.205 36.195))
    (stroke (width 0) (type default))
  )
  (wire (pts (xy 45.085 247.65) (xy 50.165 247.65))
    (stroke (width 0) (type default))
  )
  (wire (pts (xy 153.035 139.7) (xy 153.035 140.97))
    (stroke (width 0) (type default))
  )
  (wire (pts (xy 88.265 228.6) (xy 83.185 228.6))
    (stroke (width 0) (type default))
  )
  (wire (pts (xy 387.985 165.1) (xy 391.795 165.1))
    (stroke (width 0) (type default))
  )
  (wire (pts (xy 319.405 233.045) (xy 318.135 233.045))
    (stroke (width 0) (type default))
  )
  (polyline (pts (xy 187.96 109.22) (xy 187.96 285.115))
    (stroke (width 0) (type default))
  )

  (wire (pts (xy 38.1 86.995) (xy 29.845 86.995))
    (stroke (width 0) (type default))
  )
  (wire (pts (xy 285.115 53.34) (xy 285.115 49.53))
    (stroke (width 0) (type default))
  )
  (wire (pts (xy 66.04 220.345) (xy 66.04 222.25))
    (stroke (width 0) (type default))
  )
  (wire (pts (xy 259.715 160.02) (xy 271.145 160.02))
    (stroke (width 0) (type default))
  )
  (wire (pts (xy 140.97 65.405) (xy 133.35 65.405))
    (stroke (width 0) (type default))
  )
  (wire (pts (xy 93.345 134.62) (xy 100.965 134.62))
    (stroke (width 0) (type default))
  )
  (wire (pts (xy 102.87 253.365) (xy 99.06 253.365))
    (stroke (width 0) (type default))
  )
  (wire (pts (xy 198.628 22.225) (xy 202.438 22.225))
    (stroke (width 0) (type default))
  )
  (wire (pts (xy 137.795 146.05) (xy 137.795 147.32))
    (stroke (width 0) (type default))
  )
  (wire (pts (xy 319.405 198.12) (xy 319.405 205.74))
    (stroke (width 0) (type default))
  )
  (wire (pts (xy 243.205 86.36) (xy 243.205 91.44))
    (stroke (width 0) (type default))
  )
  (wire (pts (xy 247.65 203.2) (xy 248.92 203.2))
    (stroke (width 0) (type default))
  )
  (wire (pts (xy 68.58 259.715) (xy 82.55 259.715))
    (stroke (width 0) (type default))
  )
  (wire (pts (xy 66.04 29.21) (xy 86.36 29.21))
    (stroke (width 0) (type default))
  )
  (wire (pts (xy 254 259.08) (xy 254 260.35))
    (stroke (width 0) (type default))
  )
  (wire (pts (xy 379.095 206.375) (xy 381 206.375))
    (stroke (width 0) (type default))
  )
  (wire (pts (xy 379.095 151.765) (xy 365.76 151.765))
    (stroke (width 0) (type default))
  )
  (wire (pts (xy 217.17 255.905) (xy 215.265 255.905))
    (stroke (width 0) (type default))
  )
  (wire (pts (xy 66.04 153.67) (xy 66.04 151.13))
    (stroke (width 0) (type default))
  )
  (wire (pts (xy 147.955 218.44) (xy 149.86 218.44))
    (stroke (width 0) (type default))
  )
  (wire (pts (xy 274.32 44.45) (xy 290.83 44.45))
    (stroke (width 0) (type default))
  )
  (wire (pts (xy 386.08 136.525) (xy 387.985 136.525))
    (stroke (width 0) (type default))
  )
  (wire (pts (xy 311.15 41.91) (xy 335.28 41.91))
    (stroke (width 0) (type default))
  )
  (wire (pts (xy 318.135 236.855) (xy 328.93 236.855))
    (stroke (width 0) (type default))
  )
  (wire (pts (xy 66.04 151.13) (xy 67.945 151.13))
    (stroke (width 0) (type default))
  )
  (wire (pts (xy 314.96 200.66) (xy 321.31 200.66))
    (stroke (width 0) (type default))
  )
  (wire (pts (xy 81.28 256.54) (xy 81.28 253.365))
    (stroke (width 0) (type default))
  )
  (wire (pts (xy 311.15 200.66) (xy 314.96 200.66))
    (stroke (width 0) (type default))
  )
  (wire (pts (xy 307.34 24.765) (xy 311.15 24.765))
    (stroke (width 0) (type default))
  )
  (wire (pts (xy 379.095 132.08) (xy 379.095 132.715))
    (stroke (width 0) (type default))
  )
  (wire (pts (xy 311.15 24.765) (xy 311.15 31.115))
    (stroke (width 0) (type default))
  )
  (wire (pts (xy 259.08 198.12) (xy 268.605 198.12))
    (stroke (width 0) (type default))
  )
  (wire (pts (xy 265.43 245.745) (xy 272.415 245.745))
    (stroke (width 0) (type default))
  )
  (wire (pts (xy 100.965 121.285) (xy 103.505 121.285))
    (stroke (width 0) (type default))
  )
  (wire (pts (xy 248.285 255.905) (xy 237.49 255.905))
    (stroke (width 0) (type default))
  )
  (wire (pts (xy 316.865 46.99) (xy 335.28 46.99))
    (stroke (width 0) (type default))
  )
  (wire (pts (xy 210.82 71.12) (xy 226.695 71.12))
    (stroke (width 0) (type default))
  )
  (wire (pts (xy 255.905 120.015) (xy 266.7 120.015))
    (stroke (width 0) (type default))
  )
  (wire (pts (xy 163.83 44.45) (xy 163.83 47.625))
    (stroke (width 0) (type default))
  )
  (wire (pts (xy 46.355 200.66) (xy 52.705 200.66))
    (stroke (width 0) (type default))
  )
  (wire (pts (xy 165.735 198.755) (xy 165.735 196.215))
    (stroke (width 0) (type default))
  )
  (wire (pts (xy 289.56 58.42) (xy 289.56 54.61))
    (stroke (width 0) (type default))
  )
  (wire (pts (xy 207.01 120.015) (xy 218.44 120.015))
    (stroke (width 0) (type default))
  )
  (wire (pts (xy 74.295 69.85) (xy 74.295 72.39))
    (stroke (width 0) (type default))
  )
  (wire (pts (xy 107.95 253.365) (xy 113.03 253.365))
    (stroke (width 0) (type default))
  )
  (wire (pts (xy 363.22 78.74) (xy 366.395 78.74))
    (stroke (width 0) (type default))
  )
  (wire (pts (xy 72.39 86.995) (xy 72.39 89.535))
    (stroke (width 0) (type default))
  )
  (wire (pts (xy 134.62 44.45) (xy 134.62 47.625))
    (stroke (width 0) (type default))
  )
  (wire (pts (xy 70.485 86.995) (xy 72.39 86.995))
    (stroke (width 0) (type default))
  )
  (wire (pts (xy 254 245.745) (xy 265.43 245.745))
    (stroke (width 0) (type default))
  )
  (wire (pts (xy 374.65 146.685) (xy 379.095 146.685))
    (stroke (width 0) (type default))
  )
  (wire (pts (xy 386.08 206.375) (xy 387.985 206.375))
    (stroke (width 0) (type default))
  )
  (wire (pts (xy 145.415 147.32) (xy 153.035 147.32))
    (stroke (width 0) (type default))
  )
  (wire (pts (xy 134.62 44.45) (xy 141.605 44.45))
    (stroke (width 0) (type default))
  )
  (wire (pts (xy 129.54 226.06) (xy 129.54 227.33))
    (stroke (width 0) (type default))
  )
  (wire (pts (xy 387.985 136.525) (xy 387.985 137.16))
    (stroke (width 0) (type default))
  )
  (wire (pts (xy 238.76 130.175) (xy 255.905 130.175))
    (stroke (width 0) (type default))
  )
  (wire (pts (xy 93.345 132.08) (xy 103.505 132.08))
    (stroke (width 0) (type default))
  )
  (wire (pts (xy 202.438 22.225) (xy 210.693 22.225))
    (stroke (width 0) (type default))
  )
  (wire (pts (xy 125.095 156.21) (xy 108.585 156.21))
    (stroke (width 0) (type default))
  )
  (wire (pts (xy 219.075 170.18) (xy 222.25 170.18))
    (stroke (width 0) (type default))
  )
  (wire (pts (xy 210.693 57.785) (xy 210.693 55.245))
    (stroke (width 0) (type default))
  )
  (wire (pts (xy 256.54 198.12) (xy 259.08 198.12))
    (stroke (width 0) (type default))
  )
  (wire (pts (xy 387.985 196.85) (xy 391.795 196.85))
    (stroke (width 0) (type default))
  )
  (wire (pts (xy 95.25 151.13) (xy 93.345 151.13))
    (stroke (width 0) (type default))
  )
  (wire (pts (xy 259.08 208.28) (xy 259.08 210.185))
    (stroke (width 0) (type default))
  )
  (wire (pts (xy 22.86 113.665) (xy 34.29 113.665))
    (stroke (width 0) (type default))
  )
  (wire (pts (xy 138.43 253.365) (xy 138.43 259.715))
    (stroke (width 0) (type default))
  )
  (wire (pts (xy 97.155 89.535) (xy 97.155 86.995))
    (stroke (width 0) (type default))
  )
  (wire (pts (xy 374.015 196.85) (xy 379.095 196.85))
    (stroke (width 0) (type default))
  )
  (wire (pts (xy 29.21 60.96) (xy 41.91 60.96))
    (stroke (width 0) (type default))
  )
  (wire (pts (xy 386.08 146.685) (xy 387.985 146.685))
    (stroke (width 0) (type default))
  )
  (wire (pts (xy 276.225 198.12) (xy 276.225 204.47))
    (stroke (width 0) (type default))
  )
  (wire (pts (xy 125.095 148.59) (xy 125.095 149.86))
    (stroke (width 0) (type default))
  )
  (wire (pts (xy 238.76 125.095) (xy 239.395 125.095))
    (stroke (width 0) (type default))
  )
  (wire (pts (xy 80.645 86.995) (xy 80.645 89.535))
    (stroke (width 0) (type default))
  )
  (wire (pts (xy 274.32 120.015) (xy 281.94 120.015))
    (stroke (width 0) (type default))
  )
  (wire (pts (xy 393.7 93.98) (xy 394.97 93.98))
    (stroke (width 0) (type default))
  )
  (wire (pts (xy 319.405 198.12) (xy 321.31 198.12))
    (stroke (width 0) (type default))
  )
  (wire (pts (xy 322.58 52.07) (xy 335.28 52.07))
    (stroke (width 0) (type default))
  )
  (wire (pts (xy 238.125 250.825) (xy 237.49 250.825))
    (stroke (width 0) (type default))
  )
  (wire (pts (xy 322.58 85.09) (xy 322.58 86.36))
    (stroke (width 0) (type default))
  )
  (wire (pts (xy 254 260.35) (xy 254 261.62))
    (stroke (width 0) (type default))
  )
  (polyline (pts (xy 260.985 74.93) (xy 345.44 74.93))
    (stroke (width 0) (type default))
  )

  (wire (pts (xy 387.985 211.455) (xy 400.685 211.455))
    (stroke (width 0) (type default))
  )
  (wire (pts (xy 268.605 198.12) (xy 268.605 204.47))
    (stroke (width 0) (type default))
  )
  (wire (pts (xy 319.405 205.74) (xy 319.405 207.645))
    (stroke (width 0) (type default))
  )
  (wire (pts (xy 392.43 50.8) (xy 394.335 50.8))
    (stroke (width 0) (type default))
  )
  (wire (pts (xy 95.25 151.13) (xy 95.25 157.48))
    (stroke (width 0) (type default))
  )
  (wire (pts (xy 364.998 132.715) (xy 379.095 132.715))
    (stroke (width 0) (type default))
  )
  (wire (pts (xy 387.985 151.13) (xy 387.985 151.765))
    (stroke (width 0) (type default))
  )
  (wire (pts (xy 132.715 26.67) (xy 143.51 26.67))
    (stroke (width 0) (type default))
  )
  (wire (pts (xy 133.35 223.52) (xy 129.54 223.52))
    (stroke (width 0) (type default))
  )
  (polyline (pts (xy 187.325 175.26) (xy 10.795 175.26))
    (stroke (width 0) (type default))
  )

  (wire (pts (xy 144.78 196.215) (xy 144.78 198.755))
    (stroke (width 0) (type default))
  )
  (wire (pts (xy 219.075 165.1) (xy 222.25 165.1))
    (stroke (width 0) (type default))
  )
  (wire (pts (xy 110.49 139.7) (xy 112.395 139.7))
    (stroke (width 0) (type default))
  )
  (polyline (pts (xy 177.8 107.95) (xy 177.8 13.335))
    (stroke (width 0) (type default))
  )

  (wire (pts (xy 75.565 36.83) (xy 79.375 36.83))
    (stroke (width 0) (type default))
  )
  (wire (pts (xy 110.49 196.215) (xy 110.49 197.485))
    (stroke (width 0) (type default))
  )
  (wire (pts (xy 271.145 160.02) (xy 278.765 160.02))
    (stroke (width 0) (type default))
  )
  (wire (pts (xy 215.265 255.905) (xy 215.265 260.985))
    (stroke (width 0) (type default))
  )
  (wire (pts (xy 320.04 147.32) (xy 321.31 147.32))
    (stroke (width 0) (type default))
  )
  (polyline (pts (xy 260.35 107.95) (xy 260.35 13.335))
    (stroke (width 0) (type default))
  )

  (wire (pts (xy 239.395 90.17) (xy 239.395 96.52))
    (stroke (width 0) (type default))
  )
  (wire (pts (xy 129.54 226.06) (xy 133.35 226.06))
    (stroke (width 0) (type default))
  )
  (wire (pts (xy 379.095 211.455) (xy 365.76 211.455))
    (stroke (width 0) (type default))
  )
  (wire (pts (xy 311.15 187.96) (xy 321.31 187.96))
    (stroke (width 0) (type default))
  )
  (wire (pts (xy 228.6 43.815) (xy 229.87 43.815))
    (stroke (width 0) (type default))
  )
  (wire (pts (xy 46.355 142.24) (xy 46.355 144.78))
    (stroke (width 0) (type default))
  )
  (wire (pts (xy 147.955 213.36) (xy 147.955 218.44))
    (stroke (width 0) (type default))
  )
  (wire (pts (xy 313.69 132.08) (xy 313.69 129.54))
    (stroke (width 0) (type default))
  )
  (wire (pts (xy 243.205 250.825) (xy 245.11 250.825))
    (stroke (width 0) (type default))
  )
  (wire (pts (xy 192.405 85.725) (xy 192.405 86.995))
    (stroke (width 0) (type default))
  )
  (wire (pts (xy 161.29 230.505) (xy 156.845 230.505))
    (stroke (width 0) (type default))
  )
  (wire (pts (xy 99.06 259.715) (xy 102.87 259.715))
    (stroke (width 0) (type default))
  )
  (wire (pts (xy 200.533 51.435) (xy 201.803 51.435))
    (stroke (width 0) (type default))
  )
  (polyline (pts (xy 299.72 108.585) (xy 407.67 108.585))
    (stroke (width 0) (type default))
  )

  (wire (pts (xy 148.59 65.405) (xy 148.59 67.945))
    (stroke (width 0) (type default))
  )
  (wire (pts (xy 389.89 85.09) (xy 389.89 78.74))
    (stroke (width 0) (type default))
  )
  (wire (pts (xy 29.845 203.2) (xy 29.845 200.66))
    (stroke (width 0) (type default))
  )
  (wire (pts (xy 389.255 36.195) (xy 387.985 36.195))
    (stroke (width 0) (type default))
  )
  (wire (pts (xy 386.08 187.325) (xy 387.985 187.325))
    (stroke (width 0) (type default))
  )
  (wire (pts (xy 210.185 160.02) (xy 203.835 160.02))
    (stroke (width 0) (type default))
  )
  (wire (pts (xy 353.06 74.93) (xy 370.205 74.93))
    (stroke (width 0) (type default))
  )
  (wire (pts (xy 320.04 182.88) (xy 321.31 182.88))
    (stroke (width 0) (type default))
  )
  (wire (pts (xy 346.71 198.12) (xy 360.045 198.12))
    (stroke (width 0) (type default))
  )
  (wire (pts (xy 41.91 58.42) (xy 40.64 58.42))
    (stroke (width 0) (type default))
  )
  (wire (pts (xy 242.57 160.02) (xy 249.555 160.02))
    (stroke (width 0) (type default))
  )
  (wire (pts (xy 387.985 169.545) (xy 387.985 170.18))
    (stroke (width 0) (type default))
  )
  (wire (pts (xy 80.645 86.995) (xy 72.39 86.995))
    (stroke (width 0) (type default))
  )
  (wire (pts (xy 387.985 182.245) (xy 387.985 182.88))
    (stroke (width 0) (type default))
  )
  (wire (pts (xy 86.36 41.91) (xy 90.17 41.91))
    (stroke (width 0) (type default))
  )
  (wire (pts (xy 201.93 86.36) (xy 220.345 86.36))
    (stroke (width 0) (type default))
  )
  (wire (pts (xy 83.185 228.6) (xy 83.185 220.345))
    (stroke (width 0) (type default))
  )
  (wire (pts (xy 318.135 239.395) (xy 318.135 241.935))
    (stroke (width 0) (type default))
  )
  (wire (pts (xy 49.53 134.62) (xy 67.945 134.62))
    (stroke (width 0) (type default))
  )
  (wire (pts (xy 387.985 196.85) (xy 387.985 197.485))
    (stroke (width 0) (type default))
  )
  (wire (pts (xy 136.525 250.825) (xy 139.7 250.825))
    (stroke (width 0) (type default))
  )
  (wire (pts (xy 259.08 198.12) (xy 259.08 201.295))
    (stroke (width 0) (type default))
  )
  (wire (pts (xy 379.095 187.325) (xy 381 187.325))
    (stroke (width 0) (type default))
  )
  (wire (pts (xy 46.355 139.7) (xy 50.8 139.7))
    (stroke (width 0) (type default))
  )
  (wire (pts (xy 387.985 201.295) (xy 387.985 201.93))
    (stroke (width 0) (type default))
  )
  (wire (pts (xy 311.15 129.54) (xy 313.69 129.54))
    (stroke (width 0) (type default))
  )
  (wire (pts (xy 66.04 54.61) (xy 70.485 54.61))
    (stroke (width 0) (type default))
  )
  (wire (pts (xy 144.78 83.82) (xy 146.685 83.82))
    (stroke (width 0) (type default))
  )
  (wire (pts (xy 163.83 67.945) (xy 163.83 65.405))
    (stroke (width 0) (type default))
  )
  (wire (pts (xy 318.135 233.045) (xy 318.135 236.855))
    (stroke (width 0) (type default))
  )
  (wire (pts (xy 167.64 220.98) (xy 173.99 220.98))
    (stroke (width 0) (type default))
  )
  (wire (pts (xy 137.795 147.32) (xy 145.415 147.32))
    (stroke (width 0) (type default))
  )
  (wire (pts (xy 108.585 146.05) (xy 108.585 156.21))
    (stroke (width 0) (type default))
  )
  (wire (pts (xy 66.04 41.91) (xy 86.36 41.91))
    (stroke (width 0) (type default))
  )
  (wire (pts (xy 86.36 36.83) (xy 84.455 36.83))
    (stroke (width 0) (type default))
  )
  (wire (pts (xy 153.035 147.32) (xy 153.035 146.05))
    (stroke (width 0) (type default))
  )
  (wire (pts (xy 386.08 127.635) (xy 387.985 127.635))
    (stroke (width 0) (type default))
  )
  (wire (pts (xy 387.985 177.8) (xy 387.985 178.435))
    (stroke (width 0) (type default))
  )
  (wire (pts (xy 156.21 65.405) (xy 148.59 65.405))
    (stroke (width 0) (type default))
  )
  (wire (pts (xy 387.985 151.765) (xy 403.86 151.765))
    (stroke (width 0) (type default))
  )
  (wire (pts (xy 89.535 193.675) (xy 97.155 193.675))
    (stroke (width 0) (type default))
  )
  (wire (pts (xy 375.285 165.1) (xy 379.095 165.1))
    (stroke (width 0) (type default))
  )
  (wire (pts (xy 322.58 24.765) (xy 316.865 24.765))
    (stroke (width 0) (type default))
  )
  (wire (pts (xy 112.395 139.7) (xy 112.395 140.97))
    (stroke (width 0) (type default))
  )
  (wire (pts (xy 311.15 137.16) (xy 321.31 137.16))
    (stroke (width 0) (type default))
  )
  (wire (pts (xy 88.9 86.995) (xy 88.9 89.535))
    (stroke (width 0) (type default))
  )
  (wire (pts (xy 97.155 86.995) (xy 88.9 86.995))
    (stroke (width 0) (type default))
  )
  (wire (pts (xy 99.695 151.13) (xy 99.695 152.4))
    (stroke (width 0) (type default))
  )
  (wire (pts (xy 210.693 29.21) (xy 210.693 41.275))
    (stroke (width 0) (type default))
  )
  (wire (pts (xy 259.715 163.195) (xy 259.715 160.02))
    (stroke (width 0) (type default))
  )
  (wire (pts (xy 29.845 86.995) (xy 29.845 89.535))
    (stroke (width 0) (type default))
  )
  (wire (pts (xy 320.04 154.94) (xy 320.04 157.48))
    (stroke (width 0) (type default))
  )
  (wire (pts (xy 387.985 127.635) (xy 387.985 128.27))
    (stroke (width 0) (type default))
  )
  (wire (pts (xy 131.445 65.405) (xy 133.35 65.405))
    (stroke (width 0) (type default))
  )
  (wire (pts (xy 361.315 154.94) (xy 346.71 154.94))
    (stroke (width 0) (type default))
  )
  (wire (pts (xy 385.445 240.665) (xy 385.445 242.57))
    (stroke (width 0) (type default))
  )
  (wire (pts (xy 116.84 219.71) (xy 116.84 221.615))
    (stroke (width 0) (type default))
  )
  (polyline (pts (xy 345.44 74.93) (xy 345.44 107.95))
    (stroke (width 0) (type default))
  )

  (wire (pts (xy 271.145 160.02) (xy 271.145 166.37))
    (stroke (width 0) (type default))
  )
  (wire (pts (xy 319.405 195.58) (xy 321.31 195.58))
    (stroke (width 0) (type default))
  )
  (wire (pts (xy 311.15 36.195) (xy 311.15 41.91))
    (stroke (width 0) (type default))
  )
  (wire (pts (xy 316.865 31.115) (xy 316.865 24.765))
    (stroke (width 0) (type default))
  )
  (wire (pts (xy 245.11 41.275) (xy 258.953 41.275))
    (stroke (width 0) (type default))
  )
  (wire (pts (xy 80.645 52.07) (xy 99.06 52.07))
    (stroke (width 0) (type default))
  )
  (wire (pts (xy 40.64 247.65) (xy 45.085 247.65))
    (stroke (width 0) (type default))
  )
  (wire (pts (xy 321.31 144.78) (xy 320.04 144.78))
    (stroke (width 0) (type default))
  )
  (wire (pts (xy 95.25 41.91) (xy 96.52 41.91))
    (stroke (width 0) (type default))
  )
  (wire (pts (xy 387.985 74.93) (xy 394.97 74.93))
    (stroke (width 0) (type default))
  )
  (wire (pts (xy 110.49 196.215) (xy 125.73 196.215))
    (stroke (width 0) (type default))
  )
  (wire (pts (xy 266.7 120.015) (xy 274.32 120.015))
    (stroke (width 0) (type default))
  )
  (wire (pts (xy 379.095 182.88) (xy 365.76 182.88))
    (stroke (width 0) (type default))
  )
  (wire (pts (xy 308.61 46.99) (xy 316.865 46.99))
    (stroke (width 0) (type default))
  )
  (wire (pts (xy 364.49 141.605) (xy 379.095 141.605))
    (stroke (width 0) (type default))
  )
  (wire (pts (xy 382.27 240.665) (xy 385.445 240.665))
    (stroke (width 0) (type default))
  )
  (wire (pts (xy 254 252.73) (xy 254 254))
    (stroke (width 0) (type default))
  )
  (wire (pts (xy 133.35 83.82) (xy 133.35 86.36))
    (stroke (width 0) (type default))
  )
  (wire (pts (xy 131.445 83.82) (xy 133.35 83.82))
    (stroke (width 0) (type default))
  )
  (wire (pts (xy 190.5 250.825) (xy 210.185 250.825))
    (stroke (width 0) (type default))
  )
  (polyline (pts (xy 12.065 108.585) (xy 299.72 108.585))
    (stroke (width 0) (type default))
  )

  (wire (pts (xy 394.335 32.385) (xy 403.225 32.385))
    (stroke (width 0) (type default))
  )
  (wire (pts (xy 379.095 165.1) (xy 381 165.1))
    (stroke (width 0) (type default))
  )
  (wire (pts (xy 168.91 223.52) (xy 168.91 225.425))
    (stroke (width 0) (type default))
  )
  (wire (pts (xy 379.095 196.85) (xy 379.095 197.485))
    (stroke (width 0) (type default))
  )
  (wire (pts (xy 248.285 165.1) (xy 249.555 165.1))
    (stroke (width 0) (type default))
  )
  (wire (pts (xy 79.375 250.825) (xy 82.55 250.825))
    (stroke (width 0) (type default))
  )
  (wire (pts (xy 394.335 50.8) (xy 394.335 52.07))
    (stroke (width 0) (type default))
  )
  (wire (pts (xy 346.71 187.96) (xy 360.045 187.96))
    (stroke (width 0) (type default))
  )
  (wire (pts (xy 252.095 245.745) (xy 254 245.745))
    (stroke (width 0) (type default))
  )
  (wire (pts (xy 112.395 219.71) (xy 112.395 221.615))
    (stroke (width 0) (type default))
  )
  (wire (pts (xy 66.04 52.07) (xy 80.645 52.07))
    (stroke (width 0) (type default))
  )
  (wire (pts (xy 156.21 65.405) (xy 156.21 67.945))
    (stroke (width 0) (type default))
  )
  (wire (pts (xy 253.365 120.015) (xy 255.905 120.015))
    (stroke (width 0) (type default))
  )
  (wire (pts (xy 387.985 127.635) (xy 398.272 127.635))
    (stroke (width 0) (type default))
  )
  (wire (pts (xy 125.095 139.7) (xy 137.795 139.7))
    (stroke (width 0) (type default))
  )
  (wire (pts (xy 387.985 206.375) (xy 391.795 206.375))
    (stroke (width 0) (type default))
  )
  (wire (pts (xy 137.795 140.97) (xy 137.795 139.7))
    (stroke (width 0) (type default))
  )
  (wire (pts (xy 165.735 182.245) (xy 173.99 182.245))
    (stroke (width 0) (type default))
  )
  (wire (pts (xy 311.15 180.34) (xy 313.055 180.34))
    (stroke (width 0) (type default))
  )
  (wire (pts (xy 76.2 220.345) (xy 66.04 220.345))
    (stroke (width 0) (type default))
  )
  (wire (pts (xy 218.44 130.175) (xy 216.535 130.175))
    (stroke (width 0) (type default))
  )
  (wire (pts (xy 145.415 146.05) (xy 145.415 147.32))
    (stroke (width 0) (type default))
  )
  (wire (pts (xy 131.445 44.45) (xy 134.62 44.45))
    (stroke (width 0) (type default))
  )
  (wire (pts (xy 346.71 205.74) (xy 360.045 205.74))
    (stroke (width 0) (type default))
  )
  (wire (pts (xy 210.693 41.275) (xy 229.87 41.275))
    (stroke (width 0) (type default))
  )
  (wire (pts (xy 203.2 120.015) (xy 207.01 120.015))
    (stroke (width 0) (type default))
  )
  (wire (pts (xy 308.61 41.91) (xy 311.15 41.91))
    (stroke (width 0) (type default))
  )
  (wire (pts (xy 320.04 147.32) (xy 320.04 154.94))
    (stroke (width 0) (type default))
  )
  (wire (pts (xy 379.095 127.635) (xy 379.095 128.27))
    (stroke (width 0) (type default))
  )
  (wire (pts (xy 88.9 86.995) (xy 80.645 86.995))
    (stroke (width 0) (type default))
  )
  (wire (pts (xy 138.43 259.715) (xy 139.7 259.715))
    (stroke (width 0) (type default))
  )
  (wire (pts (xy 54.61 86.995) (xy 46.355 86.995))
    (stroke (width 0) (type default))
  )
  (wire (pts (xy 322.58 97.79) (xy 322.58 99.06))
    (stroke (width 0) (type default))
  )
  (wire (pts (xy 125.095 139.7) (xy 125.095 143.51))
    (stroke (width 0) (type default))
  )
  (wire (pts (xy 254 260.35) (xy 248.285 260.35))
    (stroke (width 0) (type default))
  )
  (wire (pts (xy 248.92 198.12) (xy 251.46 198.12))
    (stroke (width 0) (type default))
  )
  (wire (pts (xy 81.28 253.365) (xy 82.55 253.365))
    (stroke (width 0) (type default))
  )
  (wire (pts (xy 277.495 24.765) (xy 280.035 24.765))
    (stroke (width 0) (type default))
  )
  (wire (pts (xy 266.7 120.015) (xy 266.7 126.365))
    (stroke (width 0) (type default))
  )
  (wire (pts (xy 211.455 82.55) (xy 220.345 82.55))
    (stroke (width 0) (type default))
  )
  (wire (pts (xy 374.015 127.635) (xy 379.095 127.635))
    (stroke (width 0) (type default))
  )
  (wire (pts (xy 322.58 31.115) (xy 322.58 24.765))
    (stroke (width 0) (type default))
  )
  (wire (pts (xy 249.555 165.1) (xy 249.555 160.02))
    (stroke (width 0) (type default))
  )
  (wire (pts (xy 319.405 205.74) (xy 321.31 205.74))
    (stroke (width 0) (type default))
  )
  (wire (pts (xy 66.04 62.23) (xy 74.295 62.23))
    (stroke (width 0) (type default))
  )
  (wire (pts (xy 161.29 233.68) (xy 156.845 233.68))
    (stroke (width 0) (type default))
  )
  (wire (pts (xy 160.655 139.7) (xy 153.035 139.7))
    (stroke (width 0) (type default))
  )
  (wire (pts (xy 311.15 149.86) (xy 314.325 149.86))
    (stroke (width 0) (type default))
  )
  (wire (pts (xy 283.845 198.12) (xy 283.845 204.47))
    (stroke (width 0) (type default))
  )
  (wire (pts (xy 125.73 192.405) (xy 119.38 192.405))
    (stroke (width 0) (type default))
  )
  (wire (pts (xy 55.88 139.7) (xy 67.945 139.7))
    (stroke (width 0) (type default))
  )
  (wire (pts (xy 103.505 132.08) (xy 127.635 132.08))
    (stroke (width 0) (type default))
  )
  (wire (pts (xy 316.23 236.855) (xy 318.135 236.855))
    (stroke (width 0) (type default))
  )
  (wire (pts (xy 217.17 208.28) (xy 221.615 208.28))
    (stroke (width 0) (type default))
  )
  (wire (pts (xy 313.69 129.54) (xy 321.31 129.54))
    (stroke (width 0) (type default))
  )
  (wire (pts (xy 96.52 41.91) (xy 99.06 41.91))
    (stroke (width 0) (type default))
  )
  (wire (pts (xy 311.15 190.5) (xy 321.31 190.5))
    (stroke (width 0) (type default))
  )
  (wire (pts (xy 156.21 259.715) (xy 161.29 259.715))
    (stroke (width 0) (type default))
  )
  (wire (pts (xy 379.095 170.18) (xy 364.49 170.18))
    (stroke (width 0) (type default))
  )
  (wire (pts (xy 379.095 140.97) (xy 379.095 141.605))
    (stroke (width 0) (type default))
  )
  (wire (pts (xy 143.51 223.52) (xy 149.86 223.52))
    (stroke (width 0) (type default))
  )
  (wire (pts (xy 45.085 247.65) (xy 45.085 250.19))
    (stroke (width 0) (type default))
  )
  (wire (pts (xy 29.21 46.99) (xy 41.91 46.99))
    (stroke (width 0) (type default))
  )
  (wire (pts (xy 143.51 196.215) (xy 144.78 196.215))
    (stroke (width 0) (type default))
  )
  (wire (pts (xy 83.185 220.345) (xy 81.28 220.345))
    (stroke (width 0) (type default))
  )
  (wire (pts (xy 107.95 259.715) (xy 113.03 259.715))
    (stroke (width 0) (type default))
  )
  (wire (pts (xy 74.295 62.23) (xy 74.295 64.77))
    (stroke (width 0) (type default))
  )
  (wire (pts (xy 349.25 32.385) (xy 370.205 32.385))
    (stroke (width 0) (type default))
  )

  (text "Input power connector" (at 301.625 225.425 0)
    (effects (font (size 2.0066 2.0066) (thickness 0.4013) bold) (justify left bottom))
  )
  (text "Main supply (5V 5A)" (at 71.12 115.57 0)
    (effects (font (size 2.0066 2.0066) (thickness 0.4013) bold) (justify left bottom))
  )
  (text "Power sequencer" (at 263.525 17.145 0)
    (effects (font (size 2.0066 2.0066) (thickness 0.4013) bold) (justify left bottom))
  )
  (text "VTT_CNTL and SLP_S4 FPGA Control " (at 346.71 16.51 0)
    (effects (font (size 2 2) (thickness 0.4) bold) (justify left bottom))
  )
  (text "VCCINT (1.0V 3A)" (at 191.77 236.22 0)
    (effects (font (size 2.0066 2.0066) (thickness 0.4013) bold) (justify left bottom))
  )
  (text "By default 8s button press to turn off.\nFor instant turn off solder R219\n"
    (at 62.23 235.585 0)
    (effects (font (size 1 1)) (justify left bottom))
  )
  (text "3V3 supply (3A)" (at 191.77 114.3 0)
    (effects (font (size 2.0066 2.0066) (thickness 0.4013) bold) (justify left bottom))
  )
  (text "VTT 0.6V 1A" (at 99.06 50.165 0)
    (effects (font (size 1.27 1.27)) (justify left bottom))
  )
  (text "1V8 supply" (at 191.77 154.94 0)
    (effects (font (size 2.0066 2.0066) (thickness 0.4013) bold) (justify left bottom))
  )
  (text "VDDQ 1.2V 8A" (at 99.06 40.005 0)
    (effects (font (size 1.27 1.27)) (justify left bottom))
  )
  (text "VIN 4.5V to 18V" (at 18.415 22.225 0)
    (effects (font (size 1.27 1.27)) (justify left bottom))
  )
  (text "Plane Decoupling" (at 46.99 83.185 0)
    (effects (font (size 2.0066 2.0066) (thickness 0.4013) bold) (justify left bottom))
  )
  (text "R118: S3 controls ON/OFF" (at 14.605 187.325 0)
    (effects (font (size 1 1)) (justify left bottom))
  )
  (text "VCC5V0 4.5V to 5.5V" (at 18.415 24.765 0)
    (effects (font (size 1.27 1.27)) (justify left bottom))
  )
  (text "Power cycle " (at 178.943 17.145 0)
    (effects (font (size 2 2) (thickness 0.4) bold) (justify left bottom))
  )
  (text "140ms delay\nfixed" (at 232.41 50.8 0)
    (effects (font (size 1.27 1.27)) (justify left bottom))
  )
  (text "Filtering" (at 140.335 19.05 0)
    (effects (font (size 2.0066 2.0066) (thickness 0.4013) bold) (justify left bottom))
  )
  (text "SMBus/I2C Address \n0010 000 (R/W)" (at 301.625 172.085 0)
    (effects (font (size 1.27 1.27) (thickness 0.254) bold italic) (justify left bottom))
  )
  (text "Optional FAN connector" (at 364.49 225.425 0)
    (effects (font (size 2.0066 2.0066) (thickness 0.4013) bold) (justify left bottom))
  )
  (text "Active discharge" (at 19.05 243.84 0)
    (effects (font (size 2.0066 2.0066) (thickness 0.4013) bold) (justify left bottom))
  )
  (text "1V2 supply" (at 193.04 193.04 0)
    (effects (font (size 2.0066 2.0066) (thickness 0.4013) bold) (justify left bottom))
  )
  (text "Shunt resistors\nFuses" (at 372.11 118.11 0)
    (effects (font (size 2.0066 2.0066) (thickness 0.4013) bold) (justify left bottom))
  )
  (text "Pushbutton ON/OFF controller" (at 13.97 180.975 0)
    (effects (font (size 2.0066 2.0066) (thickness 0.4013) bold) (justify left bottom))
  )
  (text "DDR4 PMIC" (at 50.165 17.78 0)
    (effects (font (size 2.0066 2.0066) (thickness 0.4013) bold) (justify left bottom))
  )
  (text "1.0V/3A" (at 286.385 249.555 0)
    (effects (font (size 1.27 1.27)) (justify left bottom))
  )
  (text "Output" (at 126.365 62.865 0)
    (effects (font (size 0.9906 0.9906)) (justify left bottom))
  )
  (text "1.8V/3A" (at 288.29 163.195 0)
    (effects (font (size 1.27 1.27)) (justify left bottom))
  )
  (text "SMBus/I2C Address \n0011 111 (R/W)" (at 301.625 123.19 0)
    (effects (font (size 1.27 1.27) (thickness 0.254) bold italic) (justify left bottom))
  )
  (text "VPP 2.5V 1A" (at 99.06 24.765 0)
    (effects (font (size 1.27 1.27)) (justify left bottom))
  )
  (text "Input" (at 128.27 24.13 0)
    (effects (font (size 0.9906 0.9906)) (justify left bottom))
  )
  (text "Probes" (at 295.275 80.01 0)
    (effects (font (size 2.0066 2.0066) (thickness 0.4013) bold) (justify left bottom))
  )
  (text "1.2V/3A" (at 286.385 201.93 0)
    (effects (font (size 1.27 1.27)) (justify left bottom))
  )
  (text "R117: Always ON, U26 can be DNP" (at 14.605 183.515 0)
    (effects (font (size 1 1)) (justify left bottom))
  )
  (text "10n->\n~10ms\n" (at 278.13 52.705 0)
    (effects (font (size 1.27 1.27)) (justify left bottom))
  )
  (text "R118: Always ON using PoE, otherwise S3 controls ON/OFF"
    (at 14.605 185.42 0)
    (effects (font (size 1 1)) (justify left bottom))
  )
  (text "Power Monitors" (at 320.04 114.935 0)
    (effects (font (size 2.0066 2.0066) (thickness 0.4013) bold) (justify left bottom))
  )
  (text "Mount 1/3" (at 80.01 189.23 0)
    (effects (font (size 1.27 1.27)) (justify left bottom))
  )
  (text "STEP1 - VCCINT   (1.0V) for FPGA\nSTEP2 - VCCAUX (1.8V, 2.5V, 1.2V) for FPGA and DDR\nSTEP3 - VCCIO  (3.3V, 1.2V,  0.6V) for FPGA, PHY and DDR"
    (at 287.02 73.025 0)
    (effects (font (size 1.1938 1.1938)) (justify left bottom))
  )
  (text "DDR4" (at 310.515 95.885 0)
    (effects (font (size 0.9906 0.9906)) (justify left bottom))
  )

  (label "1V8_SEN_+" (at 365.76 201.93 0) (fields_autoplaced)
    (effects (font (size 1.27 1.27)) (justify left bottom))
  )
  (label "~{CLR}" (at 144.78 220.98 0) (fields_autoplaced)
    (effects (font (size 1.27 1.27)) (justify left bottom))
  )
  (label "SYS_PWR_GOOD" (at 201.93 86.36 0) (fields_autoplaced)
    (effects (font (size 1.27 1.27)) (justify left bottom))
  )
  (label "VTT_CNTL" (at 377.19 99.695 180) (fields_autoplaced)
    (effects (font (size 1.27 1.27)) (justify right bottom))
  )
  (label "VCC1V2_SEN_-" (at 361.315 154.94 180) (fields_autoplaced)
    (effects (font (size 1.27 1.27)) (justify right bottom))
  )
  (label "FPGA_PWR_DIS" (at 201.93 90.17 0) (fields_autoplaced)
    (effects (font (size 1.27 1.27)) (justify left bottom))
  )
  (label "1V8_SEN_+" (at 360.045 195.58 180) (fields_autoplaced)
    (effects (font (size 1.27 1.27)) (justify right bottom))
  )
  (label "5V0_SEN_+" (at 365.76 182.88 0) (fields_autoplaced)
    (effects (font (size 1.27 1.27)) (justify left bottom))
  )
  (label "1V0_SEN_+" (at 365.76 211.455 0) (fields_autoplaced)
    (effects (font (size 1.27 1.27)) (justify left bottom))
  )
  (label "VTTREF" (at 74.295 62.23 180) (fields_autoplaced)
    (effects (font (size 1.27 1.27)) (justify right bottom))
  )
  (label "VCC_AUX_EN" (at 349.25 55.245 0) (fields_autoplaced)
    (effects (font (size 1.27 1.27)) (justify left bottom))
  )
  (label "5V0_SEN_-" (at 360.045 182.88 180) (fields_autoplaced)
    (effects (font (size 1.27 1.27)) (justify right bottom))
  )
  (label "VCC_INT_EN" (at 68.58 259.715 0) (fields_autoplaced)
    (effects (font (size 1.27 1.27)) (justify left bottom))
  )
  (label "VCC_AUX_EN" (at 68.58 256.54 0) (fields_autoplaced)
    (effects (font (size 1.27 1.27)) (justify left bottom))
  )
  (label "SYS_PWR_GOOD" (at 127.635 132.08 180) (fields_autoplaced)
    (effects (font (size 1.27 1.27)) (justify right bottom))
  )
  (label "OUT" (at 119.38 192.405 0) (fields_autoplaced)
    (effects (font (size 1.27 1.27)) (justify left bottom))
  )
  (label "3V3_SEN_-" (at 400.685 192.405 180) (fields_autoplaced)
    (effects (font (size 1.27 1.27)) (justify right bottom))
  )
  (label "1V0_SEN_+" (at 360.045 203.2 180) (fields_autoplaced)
    (effects (font (size 1.27 1.27)) (justify right bottom))
  )
  (label "VDDQ_SEN_-" (at 403.86 141.605 180) (fields_autoplaced)
    (effects (font (size 1.27 1.27)) (justify right bottom))
  )
  (label "VTT_SEN_-" (at 360.045 147.32 180) (fields_autoplaced)
    (effects (font (size 1.27 1.27)) (justify right bottom))
  )
  (label "~{CLR}" (at 161.29 230.505 180) (fields_autoplaced)
    (effects (font (size 1.27 1.27)) (justify right bottom))
  )
  (label "VDDQ_SEN_+" (at 360.045 129.54 180) (fields_autoplaced)
    (effects (font (size 1.27 1.27)) (justify right bottom))
  )
  (label "VTT_CNTL" (at 403.86 74.93 180) (fields_autoplaced)
    (effects (font (size 1.27 1.27)) (justify right bottom))
  )
  (label "VCC1V2_SEN_+" (at 364.49 170.18 0) (fields_autoplaced)
    (effects (font (size 1.27 1.27)) (justify left bottom))
  )
  (label "~{INT}" (at 173.99 220.98 180) (fields_autoplaced)
    (effects (font (size 1.27 1.27)) (justify right bottom))
  )
  (label "3V3_SEN_+" (at 360.045 187.96 180) (fields_autoplaced)
    (effects (font (size 1.27 1.27)) (justify right bottom))
  )
  (label "SYS_EN" (at 57.785 134.62 0) (fields_autoplaced)
    (effects (font (size 1.27 1.27)) (justify left bottom))
  )
  (label "VCC1V2_SEN_+" (at 361.315 152.4 180) (fields_autoplaced)
    (effects (font (size 1.27 1.27)) (justify right bottom))
  )
  (label "5V0_SEN_+" (at 360.045 180.34 180) (fields_autoplaced)
    (effects (font (size 1.27 1.27)) (justify right bottom))
  )
  (label "OUT" (at 173.99 218.44 180) (fields_autoplaced)
    (effects (font (size 1.27 1.27)) (justify right bottom))
  )
  (label "~{INT}" (at 69.85 220.345 0) (fields_autoplaced)
    (effects (font (size 1.27 1.27)) (justify left bottom))
  )
  (label "VPP_SEN_+" (at 360.045 137.16 180) (fields_autoplaced)
    (effects (font (size 1.27 1.27)) (justify right bottom))
  )
  (label "SLP_S4" (at 403.225 32.385 180) (fields_autoplaced)
    (effects (font (size 1.27 1.27)) (justify right bottom))
  )
  (label "1V0_SEN_-" (at 400.685 211.455 180) (fields_autoplaced)
    (effects (font (size 1.27 1.27)) (justify right bottom))
  )
  (label "SYS_EN" (at 173.99 182.245 180) (fields_autoplaced)
    (effects (font (size 1.27 1.27)) (justify right bottom))
  )
  (label "VCC_IO_EN" (at 353.06 74.93 0) (fields_autoplaced)
    (effects (font (size 1.27 1.27)) (justify left bottom))
  )
  (label "VTT_SEN_+" (at 360.045 144.78 180) (fields_autoplaced)
    (effects (font (size 1.27 1.27)) (justify right bottom))
  )
  (label "~{CLR}" (at 69.85 228.6 0) (fields_autoplaced)
    (effects (font (size 1.27 1.27)) (justify left bottom))
  )
  (label "3V3_SEN_-" (at 360.045 190.5 180) (fields_autoplaced)
    (effects (font (size 1.27 1.27)) (justify right bottom))
  )
  (label "VCC_IO_EN" (at 323.85 52.07 0) (fields_autoplaced)
    (effects (font (size 1.27 1.27)) (justify left bottom))
  )
  (label "SLP_S4" (at 377.825 55.245 180) (fields_autoplaced)
    (effects (font (size 1.27 1.27)) (justify right bottom))
  )
  (label "PWR_SEQ_EN" (at 245.745 71.12 180) (fields_autoplaced)
    (effects (font (size 1.27 1.27)) (justify right bottom))
  )
  (label "VCC_AUX_EN" (at 191.77 165.1 0) (fields_autoplaced)
    (effects (font (size 1.27 1.27)) (justify left bottom))
  )
  (label "VPP_SEN_-" (at 403.86 132.715 180) (fields_autoplaced)
    (effects (font (size 1.27 1.27)) (justify right bottom))
  )
  (label "~{INT}" (at 161.29 233.68 180) (fields_autoplaced)
    (effects (font (size 1.27 1.27)) (justify right bottom))
  )
  (label "1V0_SEN_-" (at 360.045 205.74 180) (fields_autoplaced)
    (effects (font (size 1.27 1.27)) (justify right bottom))
  )
  (label "VCC_IO_EN" (at 127 259.715 0) (fields_autoplaced)
    (effects (font (size 1.27 1.27)) (justify left bottom))
  )
  (label "1V8_SEN_-" (at 360.045 198.12 180) (fields_autoplaced)
    (effects (font (size 1.27 1.27)) (justify right bottom))
  )
  (label "VCC_INT_EN" (at 323.85 41.91 0) (fields_autoplaced)
    (effects (font (size 1.27 1.27)) (justify left bottom))
  )
  (label "VDDQ_SEN_-" (at 360.045 132.08 180) (fields_autoplaced)
    (effects (font (size 1.27 1.27)) (justify right bottom))
  )
  (label "1V8_SEN_-" (at 400.685 201.93 180) (fields_autoplaced)
    (effects (font (size 1.27 1.27)) (justify right bottom))
  )
  (label "5V0_SEN_-" (at 400.685 182.88 180) (fields_autoplaced)
    (effects (font (size 1.27 1.27)) (justify right bottom))
  )
  (label "VCC_AUX_EN" (at 323.85 46.99 0) (fields_autoplaced)
    (effects (font (size 1.27 1.27)) (justify left bottom))
  )
  (label "SYS_PWR_GOOD" (at 210.82 71.12 0) (fields_autoplaced)
    (effects (font (size 1.27 1.27)) (justify left bottom))
  )
  (label "SLP_S4" (at 29.21 60.96 0) (fields_autoplaced)
    (effects (font (size 1.27 1.27)) (justify left bottom))
  )
  (label "FPGA_PWR_DIS" (at 258.953 41.275 180) (fields_autoplaced)
    (effects (font (size 1.27 1.27)) (justify right bottom))
  )
  (label "VCC_IO_EN" (at 193.04 203.2 0) (fields_autoplaced)
    (effects (font (size 1.27 1.27)) (justify left bottom))
  )
  (label "VPP_SEN_-" (at 360.045 139.7 180) (fields_autoplaced)
    (effects (font (size 1.27 1.27)) (justify right bottom))
  )
  (label "VTT_SEN_+" (at 365.76 151.765 0) (fields_autoplaced)
    (effects (font (size 1.27 1.27)) (justify left bottom))
  )
  (label "VDDQ_SEN_+" (at 364.49 141.605 0) (fields_autoplaced)
    (effects (font (size 1.27 1.27)) (justify left bottom))
  )
  (label "VCC_IO_EN" (at 349.885 99.695 0) (fields_autoplaced)
    (effects (font (size 1.27 1.27)) (justify left bottom))
  )
  (label "VCC_IO_EN" (at 191.77 125.095 0) (fields_autoplaced)
    (effects (font (size 1.27 1.27)) (justify left bottom))
  )
  (label "PWR_SEQ_EN" (at 274.32 44.45 0) (fields_autoplaced)
    (effects (font (size 1.27 1.27)) (justify left bottom))
  )
  (label "OUT" (at 88.265 228.6 180) (fields_autoplaced)
    (effects (font (size 1.27 1.27)) (justify right bottom))
  )
  (label "VTT_SEN_-" (at 403.86 151.765 180) (fields_autoplaced)
    (effects (font (size 1.27 1.27)) (justify right bottom))
  )
  (label "VPP_SEN_+" (at 364.998 132.715 0) (fields_autoplaced)
    (effects (font (size 1.27 1.27)) (justify left bottom))
  )
  (label "PWR_SEQ_EN" (at 257.175 86.36 180) (fields_autoplaced)
    (effects (font (size 1.27 1.27)) (justify right bottom))
  )
  (label "3V3_SEN_+" (at 365.76 192.405 0) (fields_autoplaced)
    (effects (font (size 1.27 1.27)) (justify left bottom))
  )
  (label "VCC1V2_SEN_-" (at 403.225 170.18 180) (fields_autoplaced)
    (effects (font (size 1.27 1.27)) (justify right bottom))
  )
  (label "VTT_CNTL" (at 29.21 63.5 0) (fields_autoplaced)
    (effects (font (size 1.27 1.27)) (justify left bottom))
  )
  (label "VCC_INT_EN" (at 190.5 250.825 0) (fields_autoplaced)
    (effects (font (size 1.27 1.27)) (justify left bottom))
  )
  (label "VCC_AUX_EN" (at 349.25 32.385 0) (fields_autoplaced)
    (effects (font (size 1.27 1.27)) (justify left bottom))
  )

  (global_label "VCC1V0" (shape input) (at 374.015 206.375 180) (fields_autoplaced)
    (effects (font (size 1.27 1.27)) (justify right))
    (property "Intersheetrefs" "${INTERSHEET_REFS}" (at -1.27 2.54 0)
      (effects (font (size 1.27 1.27)) hide)
    )
  )
  (global_label "1V2_SYS" (shape input) (at 171.45 253.365 0) (fields_autoplaced)
    (effects (font (size 1.27 1.27)) (justify left))
    (property "Intersheetrefs" "${INTERSHEET_REFS}" (at -221.615 55.88 0)
      (effects (font (size 1.27 1.27)) hide)
    )
  )
  (global_label "VCC5V0" (shape output) (at 160.655 139.7 0) (fields_autoplaced)
    (effects (font (size 1.27 1.27)) (justify left))
    (property "Intersheetrefs" "${INTERSHEET_REFS}" (at 170.1154 139.6206 0)
      (effects (font (size 1.27 1.27)) (justify left) hide)
    )
  )
  (global_label "VCC5V0" (shape input) (at 100.965 121.285 180) (fields_autoplaced)
    (effects (font (size 1.27 1.27)) (justify right))
    (property "Intersheetrefs" "${INTERSHEET_REFS}" (at -42.545 235.585 0)
      (effects (font (size 1.27 1.27)) hide)
    )
  )
  (global_label "5V_ON_OFF" (shape input) (at 108.585 219.71 180) (fields_autoplaced)
    (effects (font (size 1.27 1.27)) (justify right))
    (property "Intersheetrefs" "${INTERSHEET_REFS}" (at 95.8589 219.7894 0)
      (effects (font (size 1.27 1.27)) (justify right) hide)
    )
  )
  (global_label "1V2_SYS" (shape input) (at 391.795 165.1 0) (fields_autoplaced)
    (effects (font (size 1.27 1.27)) (justify left))
    (property "Intersheetrefs" "${INTERSHEET_REFS}" (at -1.27 -32.385 0)
      (effects (font (size 1.27 1.27)) hide)
    )
  )
  (global_label "5V0_SYS" (shape input) (at 391.795 177.8 0) (fields_autoplaced)
    (effects (font (size 1.27 1.27)) (justify left))
    (property "Intersheetrefs" "${INTERSHEET_REFS}" (at -0.635 0 0)
      (effects (font (size 1.27 1.27)) hide)
    )
  )
  (global_label "1V0_SYS" (shape input) (at 391.795 206.375 0) (fields_autoplaced)
    (effects (font (size 1.27 1.27)) (justify left))
    (property "Intersheetrefs" "${INTERSHEET_REFS}" (at -1.27 2.54 0)
      (effects (font (size 1.27 1.27)) hide)
    )
  )
  (global_label "VCC1V8" (shape input) (at 279.4 93.98 180) (fields_autoplaced)
    (effects (font (size 1.27 1.27)) (justify right))
    (property "Intersheetrefs" "${INTERSHEET_REFS}" (at 125.73 422.275 0)
      (effects (font (size 1.27 1.27)) hide)
    )
  )
  (global_label "VCC1V2" (shape input) (at 375.285 165.1 180) (fields_autoplaced)
    (effects (font (size 1.27 1.27)) (justify right))
    (property "Intersheetrefs" "${INTERSHEET_REFS}" (at 0 -32.385 0)
      (effects (font (size 1.27 1.27)) hide)
    )
  )
  (global_label "VCC0V6" (shape input) (at 374.65 146.685 180) (fields_autoplaced)
    (effects (font (size 1.27 1.27)) (justify right))
    (property "Intersheetrefs" "${INTERSHEET_REFS}" (at -1.905 -8.255 0)
      (effects (font (size 1.27 1.27)) hide)
    )
  )
  (global_label "SCL_3V3" (shape input) (at 311.15 139.7 180) (fields_autoplaced)
    (effects (font (size 1.27 1.27)) (justify right))
    (property "Intersheetrefs" "${INTERSHEET_REFS}" (at 57.785 -26.67 0)
      (effects (font (size 1.27 1.27)) hide)
    )
  )
  (global_label "5V0_SYS" (shape input) (at 359.41 28.575 180) (fields_autoplaced)
    (effects (font (size 1.27 1.27)) (justify right))
    (property "Intersheetrefs" "${INTERSHEET_REFS}" (at 751.84 206.375 0)
      (effects (font (size 1.27 1.27)) hide)
    )
  )
  (global_label "VIN" (shape input) (at 300.355 90.17 180) (fields_autoplaced)
    (effects (font (size 1.27 1.27)) (justify right))
    (property "Intersheetrefs" "${INTERSHEET_REFS}" (at 146.685 434.34 0)
      (effects (font (size 1.27 1.27)) hide)
    )
  )
  (global_label "VCC1V8" (shape output) (at 287.655 160.02 0) (fields_autoplaced)
    (effects (font (size 1.27 1.27)) (justify left))
    (property "Intersheetrefs" "${INTERSHEET_REFS}" (at 7.62 -20.955 0)
      (effects (font (size 1.27 1.27)) hide)
    )
  )
  (global_label "VCC2V5" (shape input) (at 144.78 83.82 180) (fields_autoplaced)
    (effects (font (size 1.27 1.27)) (justify right))
    (property "Intersheetrefs" "${INTERSHEET_REFS}" (at 106.045 335.915 0)
      (effects (font (size 1.27 1.27)) hide)
    )
  )
  (global_label "5V0_SYS" (shape input) (at 226.06 38.735 180) (fields_autoplaced)
    (effects (font (size 1.27 1.27)) (justify right))
    (property "Intersheetrefs" "${INTERSHEET_REFS}" (at 215.7529 38.6556 0)
      (effects (font (size 1.27 1.27)) (justify right) hide)
    )
  )
  (global_label "VPP" (shape input) (at 398.272 127.635 0) (fields_autoplaced)
    (effects (font (size 1.27 1.27)) (justify left))
    (property "Intersheetrefs" "${INTERSHEET_REFS}" (at 3.937 -17.145 0)
      (effects (font (size 1.27 1.27)) hide)
    )
  )
  (global_label "VCC1V0" (shape output) (at 286.385 245.745 0) (fields_autoplaced)
    (effects (font (size 1.27 1.27)) (justify left))
    (property "Intersheetrefs" "${INTERSHEET_REFS}" (at 172.085 16.51 0)
      (effects (font (size 1.27 1.27)) hide)
    )
  )
  (global_label "VIN" (shape input) (at 22.86 200.66 180) (fields_autoplaced)
    (effects (font (size 1.27 1.27)) (justify right))
    (property "Intersheetrefs" "${INTERSHEET_REFS}" (at -207.01 470.535 0)
      (effects (font (size 1.27 1.27)) hide)
    )
  )
  (global_label "5V0_SYS" (shape input) (at 79.375 250.825 180) (fields_autoplaced)
    (effects (font (size 1.27 1.27)) (justify right))
    (property "Intersheetrefs" "${INTERSHEET_REFS}" (at 471.805 428.625 0)
      (effects (font (size 1.27 1.27)) hide)
    )
  )
  (global_label "5V0_SYS" (shape input) (at 203.835 160.02 180) (fields_autoplaced)
    (effects (font (size 1.27 1.27)) (justify right))
    (property "Intersheetrefs" "${INTERSHEET_REFS}" (at 596.265 337.82 0)
      (effects (font (size 1.27 1.27)) hide)
    )
  )
  (global_label "5V0_SYS" (shape input) (at 136.525 250.825 180) (fields_autoplaced)
    (effects (font (size 1.27 1.27)) (justify right))
    (property "Intersheetrefs" "${INTERSHEET_REFS}" (at 528.955 428.625 0)
      (effects (font (size 1.27 1.27)) hide)
    )
  )
  (global_label "VCC2V5" (shape input) (at 300.355 92.71 180) (fields_autoplaced)
    (effects (font (size 1.27 1.27)) (justify right))
    (property "Intersheetrefs" "${INTERSHEET_REFS}" (at 116.84 417.83 0)
      (effects (font (size 1.27 1.27)) hide)
    )
  )
  (global_label "VDD1V2" (shape input) (at 373.38 136.525 180) (fields_autoplaced)
    (effects (font (size 1.27 1.27)) (justify right))
    (property "Intersheetrefs" "${INTERSHEET_REFS}" (at -3.175 -13.335 0)
      (effects (font (size 1.27 1.27)) hide)
    )
  )
  (global_label "VCC2V5" (shape input) (at 374.015 127.635 180) (fields_autoplaced)
    (effects (font (size 1.27 1.27)) (justify right))
    (property "Intersheetrefs" "${INTERSHEET_REFS}" (at -2.54 -17.145 0)
      (effects (font (size 1.27 1.27)) hide)
    )
  )
  (global_label "1V0_SYS" (shape input) (at 113.03 259.715 0) (fields_autoplaced)
    (effects (font (size 1.27 1.27)) (justify left))
    (property "Intersheetrefs" "${INTERSHEET_REFS}" (at -280.035 55.88 0)
      (effects (font (size 1.27 1.27)) hide)
    )
  )
  (global_label "5V0_SYS" (shape input) (at 131.445 44.45 180) (fields_autoplaced)
    (effects (font (size 1.27 1.27)) (justify right))
    (property "Intersheetrefs" "${INTERSHEET_REFS}" (at 93.345 224.155 0)
      (effects (font (size 1.27 1.27)) hide)
    )
  )
  (global_label "5V0_SYS" (shape input) (at 362.585 71.12 180) (fields_autoplaced)
    (effects (font (size 1.27 1.27)) (justify right))
    (property "Intersheetrefs" "${INTERSHEET_REFS}" (at 755.015 248.92 0)
      (effects (font (size 1.27 1.27)) hide)
    )
  )
  (global_label "5V0_SYS" (shape input) (at 307.34 24.765 180) (fields_autoplaced)
    (effects (font (size 1.27 1.27)) (justify right))
    (property "Intersheetrefs" "${INTERSHEET_REFS}" (at 699.77 202.565 0)
      (effects (font (size 1.27 1.27)) hide)
    )
  )
  (global_label "SDA_3V3" (shape input) (at 311.15 137.16 180) (fields_autoplaced)
    (effects (font (size 1.27 1.27)) (justify right))
    (property "Intersheetrefs" "${INTERSHEET_REFS}" (at 57.785 21.59 0)
      (effects (font (size 1.27 1.27)) hide)
    )
  )
  (global_label "VIN" (shape input) (at 156.21 182.245 180) (fields_autoplaced)
    (effects (font (size 1.27 1.27)) (justify right))
    (property "Intersheetrefs" "${INTERSHEET_REFS}" (at 11.43 245.745 0)
      (effects (font (size 1.27 1.27)) hide)
    )
  )
  (global_label "FPGA_POWER_CYCLE" (shape input) (at 200.533 51.435 180) (fields_autoplaced)
    (effects (font (size 1.27 1.27)) (justify right))
    (property "Intersheetrefs" "${INTERSHEET_REFS}" (at 179.2798 51.3556 0)
      (effects (font (size 1.27 1.27)) (justify right) hide)
    )
  )
  (global_label "VCC1V0" (shape input) (at 279.4 88.9 180) (fields_autoplaced)
    (effects (font (size 1.27 1.27)) (justify right))
    (property "Intersheetrefs" "${INTERSHEET_REFS}" (at 125.73 405.765 0)
      (effects (font (size 1.27 1.27)) hide)
    )
  )
  (global_label "5V0_SYS" (shape input) (at 198.628 22.225 180) (fields_autoplaced)
    (effects (font (size 1.27 1.27)) (justify right))
    (property "Intersheetrefs" "${INTERSHEET_REFS}" (at 188.3209 22.1456 0)
      (effects (font (size 1.27 1.27)) (justify right) hide)
    )
  )
  (global_label "3V3_SYS" (shape input) (at 311.15 149.86 180) (fields_autoplaced)
    (effects (font (size 1.27 1.27)) (justify right))
    (property "Intersheetrefs" "${INTERSHEET_REFS}" (at 300.8429 149.7806 0)
      (effects (font (size 1.27 1.27)) (justify right) hide)
    )
  )
  (global_label "VCC3V3" (shape input) (at 279.4 96.52 180) (fields_autoplaced)
    (effects (font (size 1.27 1.27)) (justify right))
    (property "Intersheetrefs" "${INTERSHEET_REFS}" (at 125.73 430.53 0)
      (effects (font (size 1.27 1.27)) hide)
    )
  )
  (global_label "5V0_SYS" (shape input) (at 211.455 82.55 180) (fields_autoplaced)
    (effects (font (size 1.27 1.27)) (justify right))
    (property "Intersheetrefs" "${INTERSHEET_REFS}" (at 603.885 260.35 0)
      (effects (font (size 1.27 1.27)) hide)
    )
  )
  (global_label "VDDQ" (shape input) (at 397.51 136.525 0) (fields_autoplaced)
    (effects (font (size 1.27 1.27)) (justify left))
    (property "Intersheetrefs" "${INTERSHEET_REFS}" (at 3.81 -13.335 0)
      (effects (font (size 1.27 1.27)) hide)
    )
  )
  (global_label "VIN" (shape input) (at 128.27 26.67 180) (fields_autoplaced)
    (effects (font (size 1.27 1.27)) (justify right))
    (property "Intersheetrefs" "${INTERSHEET_REFS}" (at 90.17 227.33 0)
      (effects (font (size 1.27 1.27)) hide)
    )
  )
  (global_label "VIN" (shape input) (at 55.88 132.08 180) (fields_autoplaced)
    (effects (font (size 1.27 1.27)) (justify right))
    (property "Intersheetrefs" "${INTERSHEET_REFS}" (at -88.9 195.58 0)
      (effects (font (size 1.27 1.27)) hide)
    )
  )
  (global_label "VIN_POE" (shape input) (at 89.535 193.675 180) (fields_autoplaced)
    (effects (font (size 1.27 1.27)) (justify right))
    (property "Intersheetrefs" "${INTERSHEET_REFS}" (at 79.4698 193.5956 0)
      (effects (font (size 1.27 1.27)) (justify right) hide)
    )
  )
  (global_label "VCC2V5" (shape input) (at 99.06 26.67 0) (fields_autoplaced)
    (effects (font (size 1.27 1.27)) (justify left))
    (property "Intersheetrefs" "${INTERSHEET_REFS}" (at -55.88 -20.955 0)
      (effects (font (size 1.27 1.27)) hide)
    )
  )
  (global_label "VCC3V3" (shape output) (at 285.115 120.015 0) (fields_autoplaced)
    (effects (font (size 1.27 1.27)) (justify left))
    (property "Intersheetrefs" "${INTERSHEET_REFS}" (at -0.635 -7.62 0)
      (effects (font (size 1.27 1.27)) hide)
    )
  )
  (global_label "3V3_SYS" (shape input) (at 171.45 259.715 0) (fields_autoplaced)
    (effects (font (size 1.27 1.27)) (justify left))
    (property "Intersheetrefs" "${INTERSHEET_REFS}" (at -220.98 76.2 0)
      (effects (font (size 1.27 1.27)) hide)
    )
  )
  (global_label "VIN" (shape input) (at 328.295 233.045 0) (fields_autoplaced)
    (effects (font (size 1.27 1.27)) (justify left))
    (property "Intersheetrefs" "${INTERSHEET_REFS}" (at 558.165 -36.83 0)
      (effects (font (size 1.27 1.27)) hide)
    )
  )
  (global_label "VIN" (shape input) (at 20.32 113.665 180) (fields_autoplaced)
    (effects (font (size 1.27 1.27)) (justify right))
    (property "Intersheetrefs" "${INTERSHEET_REFS}" (at -110.49 139.065 0)
      (effects (font (size 1.27 1.27)) hide)
    )
  )
  (global_label "5V0_SYS" (shape input) (at 277.495 24.765 180) (fields_autoplaced)
    (effects (font (size 1.27 1.27)) (justify right))
    (property "Intersheetrefs" "${INTERSHEET_REFS}" (at 669.925 202.565 0)
      (effects (font (size 1.27 1.27)) hide)
    )
  )
  (global_label "VIN_RAW" (shape output) (at 328.93 236.855 0) (fields_autoplaced)
    (effects (font (size 1.27 1.27)) (justify left))
    (property "Intersheetrefs" "${INTERSHEET_REFS}" (at 339.0556 236.7756 0)
      (effects (font (size 1.27 1.27)) (justify left) hide)
    )
  )
  (global_label "VCC0V6" (shape input) (at 300.355 97.79 180) (fields_autoplaced)
    (effects (font (size 1.27 1.27)) (justify right))
    (property "Intersheetrefs" "${INTERSHEET_REFS}" (at 116.84 433.705 0)
      (effects (font (size 1.27 1.27)) hide)
    )
  )
  (global_label "1V2_SYS" (shape input) (at 279.4 91.44 180) (fields_autoplaced)
    (effects (font (size 1.27 1.27)) (justify right))
    (property "Intersheetrefs" "${INTERSHEET_REFS}" (at 125.73 414.02 0)
      (effects (font (size 1.27 1.27)) hide)
    )
  )
  (global_label "VCC1V2" (shape output) (at 286.385 198.12 0) (fields_autoplaced)
    (effects (font (size 1.27 1.27)) (justify left))
    (property "Intersheetrefs" "${INTERSHEET_REFS}" (at 64.77 -31.75 0)
      (effects (font (size 1.27 1.27)) hide)
    )
  )
  (global_label "1V8_SYS" (shape input) (at 113.03 253.365 0) (fields_autoplaced)
    (effects (font (size 1.27 1.27)) (justify left))
    (property "Intersheetrefs" "${INTERSHEET_REFS}" (at -279.4 62.865 0)
      (effects (font (size 1.27 1.27)) hide)
    )
  )
  (global_label "VDD1V2" (shape input) (at 99.06 41.91 0) (fields_autoplaced)
    (effects (font (size 1.27 1.27)) (justify left))
    (property "Intersheetrefs" "${INTERSHEET_REFS}" (at -56.515 -17.145 0)
      (effects (font (size 1.27 1.27)) hide)
    )
  )
  (global_label "5V0_SYS" (shape input) (at 392.43 50.8 180) (fields_autoplaced)
    (effects (font (size 1.27 1.27)) (justify right))
    (property "Intersheetrefs" "${INTERSHEET_REFS}" (at 784.86 228.6 0)
      (effects (font (size 1.27 1.27)) hide)
    )
  )
  (global_label "FPGA_SLP_S4" (shape input) (at 363.855 36.195 180) (fields_autoplaced)
    (effects (font (size 1.27 1.27)) (justify right))
    (property "Intersheetrefs" "${INTERSHEET_REFS}" (at 348.9518 36.1156 0)
      (effects (font (size 1.27 1.27)) (justify right) hide)
    )
  )
  (global_label "3V3_SYS" (shape input) (at 311.15 129.54 180) (fields_autoplaced)
    (effects (font (size 1.27 1.27)) (justify right))
    (property "Intersheetrefs" "${INTERSHEET_REFS}" (at 703.58 313.055 0)
      (effects (font (size 1.27 1.27)) hide)
    )
  )
  (global_label "VCC0V6" (shape input) (at 99.06 52.07 0) (fields_autoplaced)
    (effects (font (size 1.27 1.27)) (justify left))
    (property "Intersheetrefs" "${INTERSHEET_REFS}" (at -56.515 -14.605 0)
      (effects (font (size 1.27 1.27)) hide)
    )
  )
  (global_label "5V_ON_OFF" (shape input) (at 144.78 213.36 180) (fields_autoplaced)
    (effects (font (size 1.27 1.27)) (justify right))
    (property "Intersheetrefs" "${INTERSHEET_REFS}" (at 132.0539 213.4394 0)
      (effects (font (size 1.27 1.27)) (justify right) hide)
    )
  )
  (global_label "5V0_SYS" (shape input) (at 201.295 245.745 180) (fields_autoplaced)
    (effects (font (size 1.27 1.27)) (justify right))
    (property "Intersheetrefs" "${INTERSHEET_REFS}" (at 593.725 423.545 0)
      (effects (font (size 1.27 1.27)) hide)
    )
  )
  (global_label "VPP" (shape input) (at 70.485 86.995 180) (fields_autoplaced)
    (effects (font (size 1.27 1.27)) (justify right))
    (property "Intersheetrefs" "${INTERSHEET_REFS}" (at -12.7 326.39 0)
      (effects (font (size 1.27 1.27)) hide)
    )
  )
  (global_label "5V0_SYS" (shape input) (at 191.135 85.725 180) (fields_autoplaced)
    (effects (font (size 1.27 1.27)) (justify right))
    (property "Intersheetrefs" "${INTERSHEET_REFS}" (at 583.565 263.525 0)
      (effects (font (size 1.27 1.27)) hide)
    )
  )
  (global_label "VCC1V8" (shape input) (at 374.015 196.85 180) (fields_autoplaced)
    (effects (font (size 1.27 1.27)) (justify right))
    (property "Intersheetrefs" "${INTERSHEET_REFS}" (at -1.27 6.35 0)
      (effects (font (size 1.27 1.27)) hide)
    )
  )
  (global_label "1V8_SYS" (shape input) (at 391.795 196.85 0) (fields_autoplaced)
    (effects (font (size 1.27 1.27)) (justify left))
    (property "Intersheetrefs" "${INTERSHEET_REFS}" (at -0.635 6.35 0)
      (effects (font (size 1.27 1.27)) hide)
    )
  )
  (global_label "5V0_SYS" (shape input) (at 40.64 247.65 180) (fields_autoplaced)
    (effects (font (size 1.27 1.27)) (justify right))
    (property "Intersheetrefs" "${INTERSHEET_REFS}" (at 433.07 425.45 0)
      (effects (font (size 1.27 1.27)) hide)
    )
  )
  (global_label "5V_ON_OFF" (shape input) (at 57.15 200.66 0) (fields_autoplaced)
    (effects (font (size 1.27 1.27)) (justify left))
    (property "Intersheetrefs" "${INTERSHEET_REFS}" (at 69.8761 200.5806 0)
      (effects (font (size 1.27 1.27)) (justify left) hide)
    )
  )
  (global_label "3V3_SYS" (shape input) (at 353.695 231.14 180) (fields_autoplaced)
    (effects (font (size 1.27 1.27)) (justify right))
    (property "Intersheetrefs" "${INTERSHEET_REFS}" (at 92.71 -46.355 0)
      (effects (font (size 1.27 1.27)) hide)
    )
  )
  (global_label "3V3_SYS" (shape input) (at 311.15 200.66 180) (fields_autoplaced)
    (effects (font (size 1.27 1.27)) (justify right))
    (property "Intersheetrefs" "${INTERSHEET_REFS}" (at 703.58 384.175 0)
      (effects (font (size 1.27 1.27)) hide)
    )
  )
  (global_label "VCC5V0" (shape input) (at 374.015 177.8 180) (fields_autoplaced)
    (effects (font (size 1.27 1.27)) (justify right))
    (property "Intersheetrefs" "${INTERSHEET_REFS}" (at -1.27 0 0)
      (effects (font (size 1.27 1.27)) hide)
    )
  )
  (global_label "3V3_SYS" (shape input) (at 391.795 187.325 0) (fields_autoplaced)
    (effects (font (size 1.27 1.27)) (justify left))
    (property "Intersheetrefs" "${INTERSHEET_REFS}" (at -0.635 3.81 0)
      (effects (font (size 1.27 1.27)) hide)
    )
  )
  (global_label "VDD1V2" (shape input) (at 300.355 95.25 180) (fields_autoplaced)
    (effects (font (size 1.27 1.27)) (justify right))
    (property "Intersheetrefs" "${INTERSHEET_REFS}" (at 116.84 425.45 0)
      (effects (font (size 1.27 1.27)) hide)
    )
  )
  (global_label "VTT" (shape input) (at 396.24 146.685 0) (fields_autoplaced)
    (effects (font (size 1.27 1.27)) (justify left))
    (property "Intersheetrefs" "${INTERSHEET_REFS}" (at 1.905 -8.255 0)
      (effects (font (size 1.27 1.27)) hide)
    )
  )
  (global_label "VCC3V3" (shape input) (at 374.015 187.325 180) (fields_autoplaced)
    (effects (font (size 1.27 1.27)) (justify right))
    (property "Intersheetrefs" "${INTERSHEET_REFS}" (at -1.27 3.81 0)
      (effects (font (size 1.27 1.27)) hide)
    )
  )
  (global_label "5V0_SYS" (shape input) (at 29.845 35.56 180) (fields_autoplaced)
    (effects (font (size 1.27 1.27)) (justify right))
    (property "Intersheetrefs" "${INTERSHEET_REFS}" (at 3.175 -12.065 0)
      (effects (font (size 1.27 1.27)) hide)
    )
  )
  (global_label "VIN" (shape input) (at 29.845 26.67 180) (fields_autoplaced)
    (effects (font (size 1.27 1.27)) (justify right))
    (property "Intersheetrefs" "${INTERSHEET_REFS}" (at -43.815 -28.575 0)
      (effects (font (size 1.27 1.27)) hide)
    )
  )
  (global_label "FPGA_VTT_CNTL" (shape input) (at 363.22 78.74 180) (fields_autoplaced)
    (effects (font (size 1.27 1.27)) (justify right))
    (property "Intersheetrefs" "${INTERSHEET_REFS}" (at 346.6234 78.6606 0)
      (effects (font (size 1.27 1.27)) (justify right) hide)
    )
  )
  (global_label "VIN_RAW" (shape output) (at 89.535 191.135 180) (fields_autoplaced)
    (effects (font (size 1.27 1.27)) (justify right))
    (property "Intersheetrefs" "${INTERSHEET_REFS}" (at 79.4094 191.2144 0)
      (effects (font (size 1.27 1.27)) (justify right) hide)
    )
  )
  (global_label "VCC5V0" (shape input) (at 279.4 99.06 180) (fields_autoplaced)
    (effects (font (size 1.27 1.27)) (justify right))
    (property "Intersheetrefs" "${INTERSHEET_REFS}" (at 125.73 438.15 0)
      (effects (font (size 1.27 1.27)) hide)
    )
  )
  (global_label "VCC0V6" (shape input) (at 131.445 83.82 180) (fields_autoplaced)
    (effects (font (size 1.27 1.27)) (justify right))
    (property "Intersheetrefs" "${INTERSHEET_REFS}" (at 92.71 325.755 0)
      (effects (font (size 1.27 1.27)) hide)
    )
  )
  (global_label "5V0_SYS" (shape input) (at 203.2 120.015 180) (fields_autoplaced)
    (effects (font (size 1.27 1.27)) (justify right))
    (property "Intersheetrefs" "${INTERSHEET_REFS}" (at 595.63 297.815 0)
      (effects (font (size 1.27 1.27)) hide)
    )
  )
  (global_label "VDD1V2" (shape input) (at 131.445 65.405 180) (fields_autoplaced)
    (effects (font (size 1.27 1.27)) (justify right))
    (property "Intersheetrefs" "${INTERSHEET_REFS}" (at 92.71 326.39 0)
      (effects (font (size 1.27 1.27)) hide)
    )
  )
  (global_label "VDDQ" (shape input) (at 27.94 86.995 180) (fields_autoplaced)
    (effects (font (size 1.27 1.27)) (justify right))
    (property "Intersheetrefs" "${INTERSHEET_REFS}" (at -53.975 274.955 0)
      (effects (font (size 1.27 1.27)) hide)
    )
  )
  (global_label "5V0_SYS" (shape input) (at 203.2 198.12 180) (fields_autoplaced)
    (effects (font (size 1.27 1.27)) (justify right))
    (property "Intersheetrefs" "${INTERSHEET_REFS}" (at 595.63 375.92 0)
      (effects (font (size 1.27 1.27)) hide)
    )
  )
  (global_label "5V0_SYS" (shape input) (at 393.7 93.98 180) (fields_autoplaced)
    (effects (font (size 1.27 1.27)) (justify right))
    (property "Intersheetrefs" "${INTERSHEET_REFS}" (at 786.13 271.78 0)
      (effects (font (size 1.27 1.27)) hide)
    )
  )
  (global_label "3V3_SYS" (shape input) (at 311.15 180.34 180) (fields_autoplaced)
    (effects (font (size 1.27 1.27)) (justify right))
    (property "Intersheetrefs" "${INTERSHEET_REFS}" (at 703.58 363.855 0)
      (effects (font (size 1.27 1.27)) hide)
    )
  )
  (global_label "VDD1V2" (shape input) (at 160.655 44.45 180) (fields_autoplaced)
    (effects (font (size 1.27 1.27)) (justify right))
    (property "Intersheetrefs" "${INTERSHEET_REFS}" (at 132.715 -22.86 0)
      (effects (font (size 1.27 1.27)) hide)
    )
  )
  (global_label "SDA_3V3" (shape input) (at 311.15 187.96 180) (fields_autoplaced)
    (effects (font (size 1.27 1.27)) (justify right))
    (property "Intersheetrefs" "${INTERSHEET_REFS}" (at 57.785 72.39 0)
      (effects (font (size 1.27 1.27)) hide)
    )
  )
  (global_label "SCL_3V3" (shape input) (at 311.15 190.5 180) (fields_autoplaced)
    (effects (font (size 1.27 1.27)) (justify right))
    (property "Intersheetrefs" "${INTERSHEET_REFS}" (at 57.785 24.13 0)
      (effects (font (size 1.27 1.27)) hide)
    )
  )
  (global_label "VDD1V2" (shape input) (at 29.21 46.99 180) (fields_autoplaced)
    (effects (font (size 1.27 1.27)) (justify right))
    (property "Intersheetrefs" "${INTERSHEET_REFS}" (at 1.27 -20.32 0)
      (effects (font (size 1.27 1.27)) hide)
    )
  )
  (global_label "5V_ON_OFF" (shape input) (at 122.555 188.595 180) (fields_autoplaced)
    (effects (font (size 1.27 1.27)) (justify right))
    (property "Intersheetrefs" "${INTERSHEET_REFS}" (at 109.8289 188.6744 0)
      (effects (font (size 1.27 1.27)) (justify right) hide)
    )
  )
  (global_label "5V0_SYS" (shape input) (at 387.35 235.585 0) (fields_autoplaced)
    (effects (font (size 1.27 1.27)) (justify left))
    (property "Intersheetrefs" "${INTERSHEET_REFS}" (at -5.08 57.785 0)
      (effects (font (size 1.27 1.27)) hide)
    )
  )
  (global_label "5V0_SYS" (shape input) (at 274.32 41.91 180) (fields_autoplaced)
    (effects (font (size 1.27 1.27)) (justify right))
    (property "Intersheetrefs" "${INTERSHEET_REFS}" (at 666.75 219.71 0)
      (effects (font (size 1.27 1.27)) hide)
    )
  )

  (symbol (lib_id "antmicropower:GND") (at 134.62 52.705 0) (unit 1)
    (in_bom yes) (on_board yes) (dnp no) (fields_autoplaced)
    (property "Reference" "#PWR0133" (at 134.62 59.055 0)
      (effects (font (size 1.27 1.27)) hide)
    )
    (property "Value" "GND" (at 134.62 57.785 0)
      (effects (font (size 1.27 1.27)))
    )
    (property "Footprint" "" (at 134.62 52.705 0)
      (effects (font (size 1.27 1.27)) hide)
    )
    (property "Datasheet" "" (at 134.62 52.705 0)
      (effects (font (size 1.27 1.27)) hide)
    )
    (property "Author" "Antmicro" (at 143.51 60.325 0)
      (effects (font (size 1.27 1.27) (thickness 0.15)) (justify left bottom) hide)
    )
    (property "License" "Apache-2.0" (at 143.51 62.865 0)
      (effects (font (size 1.27 1.27) (thickness 0.15)) (justify left bottom) hide)
    )
    (pin "1")
    (instances
      (project "data-center-rdimm-ddr4-tester"
        (path ""
          (reference "#PWR0133") (unit 1)
        )
      )
    )
  )

  (symbol (lib_id "antmicropower:GND") (at 141.605 52.705 0) (unit 1)
    (in_bom yes) (on_board yes) (dnp no) (fields_autoplaced)
    (property "Reference" "#PWR0134" (at 141.605 59.055 0)
      (effects (font (size 1.27 1.27)) hide)
    )
    (property "Value" "GND" (at 141.605 57.785 0)
      (effects (font (size 1.27 1.27)))
    )
    (property "Footprint" "" (at 141.605 52.705 0)
      (effects (font (size 1.27 1.27)) hide)
    )
    (property "Datasheet" "" (at 141.605 52.705 0)
      (effects (font (size 1.27 1.27)) hide)
    )
    (property "Author" "Antmicro" (at 150.495 60.325 0)
      (effects (font (size 1.27 1.27) (thickness 0.15)) (justify left bottom) hide)
    )
    (property "License" "Apache-2.0" (at 150.495 62.865 0)
      (effects (font (size 1.27 1.27) (thickness 0.15)) (justify left bottom) hide)
    )
    (pin "1")
    (instances
      (project "data-center-rdimm-ddr4-tester"
        (path ""
          (reference "#PWR0134") (unit 1)
        )
      )
    )
  )

  (symbol (lib_id "antmicropower:GND") (at 148.59 52.705 0) (unit 1)
    (in_bom yes) (on_board yes) (dnp no) (fields_autoplaced)
    (property "Reference" "#PWR0135" (at 148.59 59.055 0)
      (effects (font (size 1.27 1.27)) hide)
    )
    (property "Value" "GND" (at 148.59 57.785 0)
      (effects (font (size 1.27 1.27)))
    )
    (property "Footprint" "" (at 148.59 52.705 0)
      (effects (font (size 1.27 1.27)) hide)
    )
    (property "Datasheet" "" (at 148.59 52.705 0)
      (effects (font (size 1.27 1.27)) hide)
    )
    (property "Author" "Antmicro" (at 157.48 60.325 0)
      (effects (font (size 1.27 1.27) (thickness 0.15)) (justify left bottom) hide)
    )
    (property "License" "Apache-2.0" (at 157.48 62.865 0)
      (effects (font (size 1.27 1.27) (thickness 0.15)) (justify left bottom) hide)
    )
    (pin "1")
    (instances
      (project "data-center-rdimm-ddr4-tester"
        (path ""
          (reference "#PWR0135") (unit 1)
        )
      )
    )
  )

  (symbol (lib_id "antmicroCapacitors0603:C_1u_0603") (at 148.59 47.625 270) (unit 1)
    (in_bom yes) (on_board yes) (dnp no)
    (property "Reference" "C4" (at 149.225 48.26 90)
      (effects (font (size 1.524 1.524)) (justify left))
    )
    (property "Value" "C_1u_0603" (at 138.43 67.945 0)
      (effects (font (size 1.27 1.27) (thickness 0.15)) (justify left bottom) hide)
    )
    (property "Footprint" "antmicro-footprints:C_0603_1608Metric" (at 135.89 67.945 0)
      (effects (font (size 1.27 1.27) (thickness 0.15)) (justify left bottom) hide)
    )
    (property "Datasheet" " " (at 133.35 67.945 0)
      (effects (font (size 1.27 1.27) (thickness 0.15)) (justify left bottom) hide)
    )
    (property "Manufacturer" "Walsin" (at 128.27 67.945 0)
      (effects (font (size 1.27 1.27) (thickness 0.15)) (justify left bottom) hide)
    )
    (property "MPN" "0603YD105KAT2A" (at 130.81 67.945 0)
      (effects (font (size 1.27 1.27) (thickness 0.15)) (justify left bottom) hide)
    )
    (property "Val" "1u" (at 149.225 52.07 90)
      (effects (font (size 1.27 1.27) (thickness 0.15)) (justify left))
    )
    (property "License" "Apache-2.0" (at 125.73 67.945 0)
      (effects (font (size 1.27 1.27) (thickness 0.15)) (justify left bottom) hide)
    )
    (property "Author" "Antmicro" (at 123.19 67.945 0)
      (effects (font (size 1.27 1.27) (thickness 0.15)) (justify left bottom) hide)
    )
    (property "Voltage" "" (at 120.65 67.945 0)
      (effects (font (size 1.27 1.27)) (justify left bottom) hide)
    )
    (property "Dielectric" "" (at 118.11 67.945 0)
      (effects (font (size 1.27 1.27)) (justify left bottom) hide)
    )
    (pin "1")
    (pin "2")
    (instances
      (project "data-center-rdimm-ddr4-tester"
        (path ""
          (reference "C4") (unit 1)
        )
      )
    )
  )

  (symbol (lib_id "antmicroCapacitors0603:C_100n_0603") (at 141.605 47.625 270) (unit 1)
    (in_bom yes) (on_board yes) (dnp no)
    (property "Reference" "C2" (at 142.24 48.26 90)
      (effects (font (size 1.524 1.524)) (justify left))
    )
    (property "Value" "C_100n_0603" (at 131.445 67.945 0)
      (effects (font (size 1.27 1.27) (thickness 0.15)) (justify left bottom) hide)
    )
    (property "Footprint" "antmicro-footprints:C_0603_1608Metric" (at 128.905 67.945 0)
      (effects (font (size 1.27 1.27) (thickness 0.15)) (justify left bottom) hide)
    )
    (property "Datasheet" " " (at 126.365 67.945 0)
      (effects (font (size 1.27 1.27) (thickness 0.15)) (justify left bottom) hide)
    )
    (property "Manufacturer" "AVX" (at 121.285 67.945 0)
      (effects (font (size 1.27 1.27) (thickness 0.15)) (justify left bottom) hide)
    )
    (property "MPN" "0603YC104KAZ2A" (at 123.825 67.945 0)
      (effects (font (size 1.27 1.27) (thickness 0.15)) (justify left bottom) hide)
    )
    (property "Val" "100n" (at 142.24 52.07 90)
      (effects (font (size 1.27 1.27) (thickness 0.15)) (justify left))
    )
    (property "License" "Apache-2.0" (at 118.745 67.945 0)
      (effects (font (size 1.27 1.27) (thickness 0.15)) (justify left bottom) hide)
    )
    (property "Author" "Antmicro" (at 116.205 67.945 0)
      (effects (font (size 1.27 1.27) (thickness 0.15)) (justify left bottom) hide)
    )
    (property "Voltage" "" (at 113.665 67.945 0)
      (effects (font (size 1.27 1.27)) (justify left bottom) hide)
    )
    (property "Dielectric" "" (at 111.125 67.945 0)
      (effects (font (size 1.27 1.27)) (justify left bottom) hide)
    )
    (pin "1")
    (pin "2")
    (instances
      (project "data-center-rdimm-ddr4-tester"
        (path ""
          (reference "C2") (unit 1)
        )
      )
    )
  )

  (symbol (lib_id "antmicropower:GND") (at 132.715 33.655 0) (unit 1)
    (in_bom yes) (on_board yes) (dnp no) (fields_autoplaced)
    (property "Reference" "#PWR0136" (at 132.715 40.005 0)
      (effects (font (size 1.27 1.27)) hide)
    )
    (property "Value" "GND" (at 132.715 38.735 0)
      (effects (font (size 1.27 1.27)))
    )
    (property "Footprint" "" (at 132.715 33.655 0)
      (effects (font (size 1.27 1.27)) hide)
    )
    (property "Datasheet" "" (at 132.715 33.655 0)
      (effects (font (size 1.27 1.27)) hide)
    )
    (property "Author" "Antmicro" (at 141.605 41.275 0)
      (effects (font (size 1.27 1.27) (thickness 0.15)) (justify left bottom) hide)
    )
    (property "License" "Apache-2.0" (at 141.605 43.815 0)
      (effects (font (size 1.27 1.27) (thickness 0.15)) (justify left bottom) hide)
    )
    (pin "1")
    (instances
      (project "data-center-rdimm-ddr4-tester"
        (path ""
          (reference "#PWR0136") (unit 1)
        )
      )
    )
  )

  (symbol (lib_id "antmicropower:GND") (at 163.83 52.705 0) (unit 1)
    (in_bom yes) (on_board yes) (dnp no) (fields_autoplaced)
    (property "Reference" "#PWR0149" (at 163.83 59.055 0)
      (effects (font (size 1.27 1.27)) hide)
    )
    (property "Value" "GND" (at 163.83 57.785 0)
      (effects (font (size 1.27 1.27)))
    )
    (property "Footprint" "" (at 163.83 52.705 0)
      (effects (font (size 1.27 1.27)) hide)
    )
    (property "Datasheet" "" (at 163.83 52.705 0)
      (effects (font (size 1.27 1.27)) hide)
    )
    (property "Author" "Antmicro" (at 172.72 60.325 0)
      (effects (font (size 1.27 1.27) (thickness 0.15)) (justify left bottom) hide)
    )
    (property "License" "Apache-2.0" (at 172.72 62.865 0)
      (effects (font (size 1.27 1.27) (thickness 0.15)) (justify left bottom) hide)
    )
    (pin "1")
    (instances
      (project "data-center-rdimm-ddr4-tester"
        (path ""
          (reference "#PWR0149") (unit 1)
        )
      )
    )
  )

  (symbol (lib_id "antmicroResistors0402:R_100k_0402") (at 40.64 54.61 90) (unit 1)
    (in_bom yes) (on_board yes) (dnp no) (fields_autoplaced)
    (property "Reference" "R40" (at 38.735 50.8 90)
      (effects (font (size 1.524 1.524)) (justify left))
    )
    (property "Value" "R_100k_0402" (at 53.34 34.29 0)
      (effects (font (size 1.27 1.27) (thickness 0.15)) (justify left bottom) hide)
    )
    (property "Footprint" "antmicro-footprints:R_0402_1005Metric" (at 55.88 34.29 0)
      (effects (font (size 1.27 1.27) (thickness 0.15)) (justify left bottom) hide)
    )
    (property "Datasheet" "https://www.bourns.com/docs/product-datasheets/cr.pdf" (at 58.42 34.29 0)
      (effects (font (size 1.27 1.27) (thickness 0.15)) (justify left bottom) hide)
    )
    (property "Manufacturer" "Bourns" (at 63.5 34.29 0)
      (effects (font (size 1.27 1.27) (thickness 0.15)) (justify left bottom) hide)
    )
    (property "MPN" "CR0402-FX-1003GLF" (at 60.96 34.29 0)
      (effects (font (size 1.27 1.27) (thickness 0.15)) (justify left bottom) hide)
    )
    (property "Val" "100k" (at 38.735 53.9749 90)
      (effects (font (size 1.27 1.27) (thickness 0.15)) (justify left))
    )
    (property "License" "Apache-2.0" (at 66.04 34.29 0)
      (effects (font (size 1.27 1.27) (thickness 0.15)) (justify left bottom) hide)
    )
    (property "Author" "Antmicro" (at 68.58 34.29 0)
      (effects (font (size 1.27 1.27) (thickness 0.15)) (justify left bottom) hide)
    )
    (property "Tolerance" "1%" (at 50.8 34.29 0)
      (effects (font (size 1.27 1.27)) (justify left bottom) hide)
    )
    (pin "1")
    (pin "2")
    (instances
      (project "data-center-rdimm-ddr4-tester"
        (path ""
          (reference "R40") (unit 1)
        )
      )
    )
  )

  (symbol (lib_id "antmicroCapacitors0603:C_22u_0603") (at 146.685 86.36 270) (unit 1)
    (in_bom yes) (on_board yes) (dnp no)
    (property "Reference" "C31" (at 147.32 86.995 90)
      (effects (font (size 1.524 1.524)) (justify left))
    )
    (property "Value" "C_22u_0603" (at 136.525 106.68 0)
      (effects (font (size 1.27 1.27) (thickness 0.15)) (justify left bottom) hide)
    )
    (property "Footprint" "antmicro-footprints:C_0603_1608Metric" (at 133.985 106.68 0)
      (effects (font (size 1.27 1.27) (thickness 0.15)) (justify left bottom) hide)
    )
    (property "Datasheet" " " (at 131.445 106.68 0)
      (effects (font (size 1.27 1.27) (thickness 0.15)) (justify left bottom) hide)
    )
    (property "Manufacturer" "Murata" (at 126.365 106.68 0)
      (effects (font (size 1.27 1.27) (thickness 0.15)) (justify left bottom) hide)
    )
    (property "MPN" "GRM188R60J226MEA0D" (at 128.905 106.68 0)
      (effects (font (size 1.27 1.27) (thickness 0.15)) (justify left bottom) hide)
    )
    (property "Val" "22u" (at 147.32 90.805 90)
      (effects (font (size 1.27 1.27) (thickness 0.15)) (justify left))
    )
    (property "License" "Apache-2.0" (at 123.825 106.68 0)
      (effects (font (size 1.27 1.27) (thickness 0.15)) (justify left bottom) hide)
    )
    (property "Author" "Antmicro" (at 121.285 106.68 0)
      (effects (font (size 1.27 1.27) (thickness 0.15)) (justify left bottom) hide)
    )
    (property "Voltage" "" (at 118.745 106.68 0)
      (effects (font (size 1.27 1.27)) (justify left bottom) hide)
    )
    (property "Dielectric" "" (at 116.205 106.68 0)
      (effects (font (size 1.27 1.27)) (justify left bottom) hide)
    )
    (pin "1")
    (pin "2")
    (instances
      (project "data-center-rdimm-ddr4-tester"
        (path ""
          (reference "C31") (unit 1)
        )
      )
    )
  )

  (symbol (lib_id "antmicropower:GND") (at 146.685 91.44 0) (unit 1)
    (in_bom yes) (on_board yes) (dnp no) (fields_autoplaced)
    (property "Reference" "#PWR05" (at 146.685 97.79 0)
      (effects (font (size 1.27 1.27)) hide)
    )
    (property "Value" "GND" (at 146.685 96.52 0)
      (effects (font (size 1.27 1.27)))
    )
    (property "Footprint" "" (at 146.685 91.44 0)
      (effects (font (size 1.27 1.27)) hide)
    )
    (property "Datasheet" "" (at 146.685 91.44 0)
      (effects (font (size 1.27 1.27)) hide)
    )
    (property "Author" "Antmicro" (at 155.575 99.06 0)
      (effects (font (size 1.27 1.27) (thickness 0.15)) (justify left bottom) hide)
    )
    (property "License" "Apache-2.0" (at 155.575 101.6 0)
      (effects (font (size 1.27 1.27) (thickness 0.15)) (justify left bottom) hide)
    )
    (pin "1")
    (instances
      (project "data-center-rdimm-ddr4-tester"
        (path ""
          (reference "#PWR05") (unit 1)
        )
      )
    )
  )

  (symbol (lib_id "data-center-rdimm-ddr4-tester:LM3881MME_NOPB") (at 290.83 41.91 0) (unit 1)
    (in_bom yes) (on_board yes) (dnp no)
    (property "Reference" "U10" (at 299.72 35.56 0)
      (effects (font (size 1.524 1.524)))
    )
    (property "Value" "LM3881MME_NOPB" (at 299.72 36.83 0)
      (effects (font (size 1.27 1.27) (thickness 0.15)) hide)
    )
    (property "Footprint" "data-center-rdimm-ddr4-tester-footprints:VSSOP-8_3x3mm_P0.65mm" (at 334.01 49.53 0)
      (effects (font (size 1.27 1.27) (thickness 0.15)) (justify left bottom) hide)
    )
    (property "Datasheet" "http://www.ti.com/lit/ds/symlink/lm3881.pdf" (at 334.01 52.07 0)
      (effects (font (size 1.27 1.27) (thickness 0.15)) (justify left bottom) hide)
    )
    (property "Manufacturer" "Texas Instruments" (at 334.01 54.61 0)
      (effects (font (size 1.27 1.27) (thickness 0.15)) (justify left bottom) hide)
    )
    (property "MPN" "LM3881MME/NOPB" (at 299.72 38.1 0)
      (effects (font (size 1.27 1.27) (thickness 0.15)))
    )
    (property "Author" "Antmicro" (at 334.01 59.69 0)
      (effects (font (size 1.27 1.27) (thickness 0.15)) (justify left bottom) hide)
    )
    (property "License" "Apache-2.0" (at 334.01 62.23 0)
      (effects (font (size 1.27 1.27) (thickness 0.15)) (justify left bottom) hide)
    )
    (pin "1")
    (pin "2")
    (pin "3")
    (pin "4")
    (pin "5")
    (pin "6")
    (pin "7")
    (pin "8")
    (instances
      (project "data-center-rdimm-ddr4-tester"
        (path ""
          (reference "U10") (unit 1)
        )
      )
    )
  )

  (symbol (lib_id "antmicroCapacitors0402:C_100n_0402") (at 280.035 26.67 270) (unit 1)
    (in_bom yes) (on_board yes) (dnp no) (fields_autoplaced)
    (property "Reference" "C101" (at 283.21 27.9463 90)
      (effects (font (size 1.524 1.524)) (justify left))
    )
    (property "Value" "C_100n_0402" (at 269.875 46.99 0)
      (effects (font (size 1.27 1.27) (thickness 0.15)) (justify left bottom) hide)
    )
    (property "Footprint" "antmicro-footprints:C_0402_1005Metric" (at 267.335 46.99 0)
      (effects (font (size 1.27 1.27) (thickness 0.15)) (justify left bottom) hide)
    )
    (property "Datasheet" "https://search.murata.co.jp/Ceramy/image/img/A01X/G101/ENG/GRM155R61H104KE14-01.pdf" (at 264.795 46.99 0)
      (effects (font (size 1.27 1.27) (thickness 0.15)) (justify left bottom) hide)
    )
    (property "Manufacturer" "Murata" (at 259.715 46.99 0)
      (effects (font (size 1.27 1.27) (thickness 0.15)) (justify left bottom) hide)
    )
    (property "MPN" "GRM155R61H104KE14D" (at 262.255 46.99 0)
      (effects (font (size 1.27 1.27) (thickness 0.15)) (justify left bottom) hide)
    )
    (property "Val" "100n" (at 283.21 31.1212 90)
      (effects (font (size 1.27 1.27) (thickness 0.15)) (justify left))
    )
    (property "License" "Apache-2.0" (at 257.175 46.99 0)
      (effects (font (size 1.27 1.27) (thickness 0.15)) (justify left bottom) hide)
    )
    (property "Author" "Antmicro" (at 254.635 46.99 0)
      (effects (font (size 1.27 1.27) (thickness 0.15)) (justify left bottom) hide)
    )
    (property "Voltage" "50V" (at 252.095 46.99 0)
      (effects (font (size 1.27 1.27)) (justify left bottom) hide)
    )
    (property "Dielectric" "X5R" (at 249.555 46.99 0)
      (effects (font (size 1.27 1.27)) (justify left bottom) hide)
    )
    (pin "1")
    (pin "2")
    (instances
      (project "data-center-rdimm-ddr4-tester"
        (path ""
          (reference "C101") (unit 1)
        )
      )
    )
  )

  (symbol (lib_id "antmicroCapacitors0402:C_100n_0402") (at 79.375 36.83 0) (unit 1)
    (in_bom yes) (on_board yes) (dnp no)
    (property "Reference" "C35" (at 78.74 35.56 0)
      (effects (font (size 1.524 1.524)))
    )
    (property "Value" "C_100n_0402" (at 99.695 46.99 0)
      (effects (font (size 1.27 1.27) (thickness 0.15)) (justify left bottom) hide)
    )
    (property "Footprint" "antmicro-footprints:C_0402_1005Metric" (at 99.695 49.53 0)
      (effects (font (size 1.27 1.27) (thickness 0.15)) (justify left bottom) hide)
    )
    (property "Datasheet" "https://search.murata.co.jp/Ceramy/image/img/A01X/G101/ENG/GRM155R61H104KE14-01.pdf" (at 99.695 52.07 0)
      (effects (font (size 1.27 1.27) (thickness 0.15)) (justify left bottom) hide)
    )
    (property "Manufacturer" "Murata" (at 99.695 57.15 0)
      (effects (font (size 1.27 1.27) (thickness 0.15)) (justify left bottom) hide)
    )
    (property "MPN" "GRM155R61H104KE14D" (at 99.695 54.61 0)
      (effects (font (size 1.27 1.27) (thickness 0.15)) (justify left bottom) hide)
    )
    (property "Val" "100n" (at 78.74 38.1 0)
      (effects (font (size 1.27 1.27) (thickness 0.15)))
    )
    (property "License" "Apache-2.0" (at 99.695 59.69 0)
      (effects (font (size 1.27 1.27) (thickness 0.15)) (justify left bottom) hide)
    )
    (property "Author" "Antmicro" (at 99.695 62.23 0)
      (effects (font (size 1.27 1.27) (thickness 0.15)) (justify left bottom) hide)
    )
    (property "Voltage" "50V" (at 99.695 64.77 0)
      (effects (font (size 1.27 1.27)) (justify left bottom) hide)
    )
    (property "Dielectric" "X5R" (at 99.695 67.31 0)
      (effects (font (size 1.27 1.27)) (justify left bottom) hide)
    )
    (pin "1")
    (pin "2")
    (instances
      (project "data-center-rdimm-ddr4-tester"
        (path ""
          (reference "C35") (unit 1)
        )
      )
    )
  )

  (symbol (lib_id "antmicroResistors0402:R_0R_0402") (at 274.32 53.34 270) (unit 1)
    (in_bom yes) (on_board yes) (dnp no) (fields_autoplaced)
    (property "Reference" "R55" (at 271.78 54.61 90)
      (effects (font (size 1.524 1.524)) (justify right))
    )
    (property "Value" "R_0R_0402" (at 261.62 73.66 0)
      (effects (font (size 1.27 1.27) (thickness 0.15)) (justify left bottom) hide)
    )
    (property "Footprint" "antmicro-footprints:R_0402_1005Metric" (at 259.08 73.66 0)
      (effects (font (size 1.27 1.27) (thickness 0.15)) (justify left bottom) hide)
    )
    (property "Datasheet" "https://industrial.panasonic.com/cdbs/www-data/pdf/RDA0000/AOA0000C301.pdf" (at 256.54 73.66 0)
      (effects (font (size 1.27 1.27) (thickness 0.15)) (justify left bottom) hide)
    )
    (property "Manufacturer" "Panasonic" (at 251.46 73.66 0)
      (effects (font (size 1.27 1.27) (thickness 0.15)) (justify left bottom) hide)
    )
    (property "MPN" "ERJ2GE0R00X" (at 254 73.66 0)
      (effects (font (size 1.27 1.27) (thickness 0.15)) (justify left bottom) hide)
    )
    (property "Val" "0R" (at 271.78 57.7849 90)
      (effects (font (size 1.27 1.27) (thickness 0.15)) (justify right))
    )
    (property "License" "Apache-2.0" (at 248.92 73.66 0)
      (effects (font (size 1.27 1.27) (thickness 0.15)) (justify left bottom) hide)
    )
    (property "Author" "Antmicro" (at 246.38 73.66 0)
      (effects (font (size 1.27 1.27) (thickness 0.15)) (justify left bottom) hide)
    )
    (property "Tolerance" "~" (at 264.16 73.66 0)
      (effects (font (size 1.27 1.27)) (justify left bottom) hide)
    )
    (property "Current" "1A" (at 243.84 73.66 0)
      (effects (font (size 1.27 1.27) (thickness 0.15)) (justify left bottom) hide)
    )
    (pin "1")
    (pin "2")
    (instances
      (project "data-center-rdimm-ddr4-tester"
        (path ""
          (reference "R55") (unit 1)
        )
      )
    )
  )

  (symbol (lib_id "antmicroCapacitors0603:C_22u_0603") (at 133.35 67.945 270) (unit 1)
    (in_bom yes) (on_board yes) (dnp no)
    (property "Reference" "C39" (at 133.985 68.58 90)
      (effects (font (size 1.524 1.524)) (justify left))
    )
    (property "Value" "C_22u_0603" (at 123.19 88.265 0)
      (effects (font (size 1.27 1.27) (thickness 0.15)) (justify left bottom) hide)
    )
    (property "Footprint" "antmicro-footprints:C_0603_1608Metric" (at 120.65 88.265 0)
      (effects (font (size 1.27 1.27) (thickness 0.15)) (justify left bottom) hide)
    )
    (property "Datasheet" " " (at 118.11 88.265 0)
      (effects (font (size 1.27 1.27) (thickness 0.15)) (justify left bottom) hide)
    )
    (property "Manufacturer" "Murata" (at 113.03 88.265 0)
      (effects (font (size 1.27 1.27) (thickness 0.15)) (justify left bottom) hide)
    )
    (property "MPN" "GRM188R60J226MEA0D" (at 115.57 88.265 0)
      (effects (font (size 1.27 1.27) (thickness 0.15)) (justify left bottom) hide)
    )
    (property "Val" "22u" (at 133.985 72.39 90)
      (effects (font (size 1.27 1.27) (thickness 0.15)) (justify left))
    )
    (property "License" "Apache-2.0" (at 110.49 88.265 0)
      (effects (font (size 1.27 1.27) (thickness 0.15)) (justify left bottom) hide)
    )
    (property "Author" "Antmicro" (at 107.95 88.265 0)
      (effects (font (size 1.27 1.27) (thickness 0.15)) (justify left bottom) hide)
    )
    (property "Voltage" "" (at 105.41 88.265 0)
      (effects (font (size 1.27 1.27)) (justify left bottom) hide)
    )
    (property "Dielectric" "" (at 102.87 88.265 0)
      (effects (font (size 1.27 1.27)) (justify left bottom) hide)
    )
    (pin "1")
    (pin "2")
    (instances
      (project "data-center-rdimm-ddr4-tester"
        (path ""
          (reference "C39") (unit 1)
        )
      )
    )
  )

  (symbol (lib_id "antmicropower:GND") (at 133.35 73.025 0) (unit 1)
    (in_bom yes) (on_board yes) (dnp no) (fields_autoplaced)
    (property "Reference" "#PWR0151" (at 133.35 79.375 0)
      (effects (font (size 1.27 1.27)) hide)
    )
    (property "Value" "GND" (at 133.35 78.105 0)
      (effects (font (size 1.27 1.27)))
    )
    (property "Footprint" "" (at 133.35 73.025 0)
      (effects (font (size 1.27 1.27)) hide)
    )
    (property "Datasheet" "" (at 133.35 73.025 0)
      (effects (font (size 1.27 1.27)) hide)
    )
    (property "Author" "Antmicro" (at 142.24 80.645 0)
      (effects (font (size 1.27 1.27) (thickness 0.15)) (justify left bottom) hide)
    )
    (property "License" "Apache-2.0" (at 142.24 83.185 0)
      (effects (font (size 1.27 1.27) (thickness 0.15)) (justify left bottom) hide)
    )
    (pin "1")
    (instances
      (project "data-center-rdimm-ddr4-tester"
        (path ""
          (reference "#PWR0151") (unit 1)
        )
      )
    )
  )

  (symbol (lib_id "antmicroCapacitors0603:C_22u_0603") (at 140.97 67.945 270) (unit 1)
    (in_bom yes) (on_board yes) (dnp no)
    (property "Reference" "C40" (at 141.605 68.58 90)
      (effects (font (size 1.524 1.524)) (justify left))
    )
    (property "Value" "C_22u_0603" (at 130.81 88.265 0)
      (effects (font (size 1.27 1.27) (thickness 0.15)) (justify left bottom) hide)
    )
    (property "Footprint" "antmicro-footprints:C_0603_1608Metric" (at 128.27 88.265 0)
      (effects (font (size 1.27 1.27) (thickness 0.15)) (justify left bottom) hide)
    )
    (property "Datasheet" " " (at 125.73 88.265 0)
      (effects (font (size 1.27 1.27) (thickness 0.15)) (justify left bottom) hide)
    )
    (property "Manufacturer" "Murata" (at 120.65 88.265 0)
      (effects (font (size 1.27 1.27) (thickness 0.15)) (justify left bottom) hide)
    )
    (property "MPN" "GRM188R60J226MEA0D" (at 123.19 88.265 0)
      (effects (font (size 1.27 1.27) (thickness 0.15)) (justify left bottom) hide)
    )
    (property "Val" "22u" (at 141.605 72.39 90)
      (effects (font (size 1.27 1.27) (thickness 0.15)) (justify left))
    )
    (property "License" "Apache-2.0" (at 118.11 88.265 0)
      (effects (font (size 1.27 1.27) (thickness 0.15)) (justify left bottom) hide)
    )
    (property "Author" "Antmicro" (at 115.57 88.265 0)
      (effects (font (size 1.27 1.27) (thickness 0.15)) (justify left bottom) hide)
    )
    (property "Voltage" "" (at 113.03 88.265 0)
      (effects (font (size 1.27 1.27)) (justify left bottom) hide)
    )
    (property "Dielectric" "" (at 110.49 88.265 0)
      (effects (font (size 1.27 1.27)) (justify left bottom) hide)
    )
    (pin "1")
    (pin "2")
    (instances
      (project "data-center-rdimm-ddr4-tester"
        (path ""
          (reference "C40") (unit 1)
        )
      )
    )
  )

  (symbol (lib_id "antmicropower:GND") (at 140.97 73.025 0) (unit 1)
    (in_bom yes) (on_board yes) (dnp no) (fields_autoplaced)
    (property "Reference" "#PWR0152" (at 140.97 79.375 0)
      (effects (font (size 1.27 1.27)) hide)
    )
    (property "Value" "GND" (at 140.97 78.105 0)
      (effects (font (size 1.27 1.27)))
    )
    (property "Footprint" "" (at 140.97 73.025 0)
      (effects (font (size 1.27 1.27)) hide)
    )
    (property "Datasheet" "" (at 140.97 73.025 0)
      (effects (font (size 1.27 1.27)) hide)
    )
    (property "Author" "Antmicro" (at 149.86 80.645 0)
      (effects (font (size 1.27 1.27) (thickness 0.15)) (justify left bottom) hide)
    )
    (property "License" "Apache-2.0" (at 149.86 83.185 0)
      (effects (font (size 1.27 1.27) (thickness 0.15)) (justify left bottom) hide)
    )
    (pin "1")
    (instances
      (project "data-center-rdimm-ddr4-tester"
        (path ""
          (reference "#PWR0152") (unit 1)
        )
      )
    )
  )

  (symbol (lib_id "antmicroCapacitors0603:C_22u_0603") (at 148.59 67.945 270) (unit 1)
    (in_bom yes) (on_board yes) (dnp no)
    (property "Reference" "C41" (at 149.225 68.58 90)
      (effects (font (size 1.524 1.524)) (justify left))
    )
    (property "Value" "C_22u_0603" (at 138.43 88.265 0)
      (effects (font (size 1.27 1.27) (thickness 0.15)) (justify left bottom) hide)
    )
    (property "Footprint" "antmicro-footprints:C_0603_1608Metric" (at 135.89 88.265 0)
      (effects (font (size 1.27 1.27) (thickness 0.15)) (justify left bottom) hide)
    )
    (property "Datasheet" " " (at 133.35 88.265 0)
      (effects (font (size 1.27 1.27) (thickness 0.15)) (justify left bottom) hide)
    )
    (property "Manufacturer" "Murata" (at 128.27 88.265 0)
      (effects (font (size 1.27 1.27) (thickness 0.15)) (justify left bottom) hide)
    )
    (property "MPN" "GRM188R60J226MEA0D" (at 130.81 88.265 0)
      (effects (font (size 1.27 1.27) (thickness 0.15)) (justify left bottom) hide)
    )
    (property "Val" "22u" (at 149.225 72.39 90)
      (effects (font (size 1.27 1.27) (thickness 0.15)) (justify left))
    )
    (property "License" "Apache-2.0" (at 125.73 88.265 0)
      (effects (font (size 1.27 1.27) (thickness 0.15)) (justify left bottom) hide)
    )
    (property "Author" "Antmicro" (at 123.19 88.265 0)
      (effects (font (size 1.27 1.27) (thickness 0.15)) (justify left bottom) hide)
    )
    (property "Voltage" "" (at 120.65 88.265 0)
      (effects (font (size 1.27 1.27)) (justify left bottom) hide)
    )
    (property "Dielectric" "" (at 118.11 88.265 0)
      (effects (font (size 1.27 1.27)) (justify left bottom) hide)
    )
    (pin "1")
    (pin "2")
    (instances
      (project "data-center-rdimm-ddr4-tester"
        (path ""
          (reference "C41") (unit 1)
        )
      )
    )
  )

  (symbol (lib_id "antmicropower:GND") (at 148.59 73.025 0) (unit 1)
    (in_bom yes) (on_board yes) (dnp no) (fields_autoplaced)
    (property "Reference" "#PWR0153" (at 148.59 79.375 0)
      (effects (font (size 1.27 1.27)) hide)
    )
    (property "Value" "GND" (at 148.59 78.105 0)
      (effects (font (size 1.27 1.27)))
    )
    (property "Footprint" "" (at 148.59 73.025 0)
      (effects (font (size 1.27 1.27)) hide)
    )
    (property "Datasheet" "" (at 148.59 73.025 0)
      (effects (font (size 1.27 1.27)) hide)
    )
    (property "Author" "Antmicro" (at 157.48 80.645 0)
      (effects (font (size 1.27 1.27) (thickness 0.15)) (justify left bottom) hide)
    )
    (property "License" "Apache-2.0" (at 157.48 83.185 0)
      (effects (font (size 1.27 1.27) (thickness 0.15)) (justify left bottom) hide)
    )
    (pin "1")
    (instances
      (project "data-center-rdimm-ddr4-tester"
        (path ""
          (reference "#PWR0153") (unit 1)
        )
      )
    )
  )

  (symbol (lib_id "antmicroCapacitors0603:C_10n_0603") (at 285.115 53.34 270) (unit 1)
    (in_bom yes) (on_board yes) (dnp no) (fields_autoplaced)
    (property "Reference" "C100" (at 281.94 54.6163 90)
      (effects (font (size 1.524 1.524)) (justify right))
    )
    (property "Value" "C_10n_0603" (at 274.955 73.66 0)
      (effects (font (size 1.27 1.27) (thickness 0.15)) (justify left bottom) hide)
    )
    (property "Footprint" "antmicro-footprints:C_0603_1608Metric" (at 272.415 73.66 0)
      (effects (font (size 1.27 1.27) (thickness 0.15)) (justify left bottom) hide)
    )
    (property "Datasheet" " " (at 269.875 73.66 0)
      (effects (font (size 1.27 1.27) (thickness 0.15)) (justify left bottom) hide)
    )
    (property "Manufacturer" "AVX" (at 264.795 73.66 0)
      (effects (font (size 1.27 1.27) (thickness 0.15)) (justify left bottom) hide)
    )
    (property "MPN" "06031C103JAT2A" (at 267.335 73.66 0)
      (effects (font (size 1.27 1.27) (thickness 0.15)) (justify left bottom) hide)
    )
    (property "Val" "10n" (at 281.94 57.7912 90)
      (effects (font (size 1.27 1.27) (thickness 0.15)) (justify right))
    )
    (property "License" "Apache-2.0" (at 262.255 73.66 0)
      (effects (font (size 1.27 1.27) (thickness 0.15)) (justify left bottom) hide)
    )
    (property "Author" "Antmicro" (at 259.715 73.66 0)
      (effects (font (size 1.27 1.27) (thickness 0.15)) (justify left bottom) hide)
    )
    (property "Voltage" "" (at 257.175 73.66 0)
      (effects (font (size 1.27 1.27)) (justify left bottom) hide)
    )
    (property "Dielectric" "" (at 254.635 73.66 0)
      (effects (font (size 1.27 1.27)) (justify left bottom) hide)
    )
    (pin "1")
    (pin "2")
    (instances
      (project "data-center-rdimm-ddr4-tester"
        (path ""
          (reference "C100") (unit 1)
        )
      )
    )
  )

  (symbol (lib_id "antmicroCapacitors0603:C_22u_0603") (at 156.21 67.945 270) (unit 1)
    (in_bom yes) (on_board yes) (dnp no)
    (property "Reference" "C42" (at 156.845 68.58 90)
      (effects (font (size 1.524 1.524)) (justify left))
    )
    (property "Value" "C_22u_0603" (at 146.05 88.265 0)
      (effects (font (size 1.27 1.27) (thickness 0.15)) (justify left bottom) hide)
    )
    (property "Footprint" "antmicro-footprints:C_0603_1608Metric" (at 143.51 88.265 0)
      (effects (font (size 1.27 1.27) (thickness 0.15)) (justify left bottom) hide)
    )
    (property "Datasheet" " " (at 140.97 88.265 0)
      (effects (font (size 1.27 1.27) (thickness 0.15)) (justify left bottom) hide)
    )
    (property "Manufacturer" "Murata" (at 135.89 88.265 0)
      (effects (font (size 1.27 1.27) (thickness 0.15)) (justify left bottom) hide)
    )
    (property "MPN" "GRM188R60J226MEA0D" (at 138.43 88.265 0)
      (effects (font (size 1.27 1.27) (thickness 0.15)) (justify left bottom) hide)
    )
    (property "Val" "22u" (at 156.845 72.39 90)
      (effects (font (size 1.27 1.27) (thickness 0.15)) (justify left))
    )
    (property "License" "Apache-2.0" (at 133.35 88.265 0)
      (effects (font (size 1.27 1.27) (thickness 0.15)) (justify left bottom) hide)
    )
    (property "Author" "Antmicro" (at 130.81 88.265 0)
      (effects (font (size 1.27 1.27) (thickness 0.15)) (justify left bottom) hide)
    )
    (property "Voltage" "" (at 128.27 88.265 0)
      (effects (font (size 1.27 1.27)) (justify left bottom) hide)
    )
    (property "Dielectric" "" (at 125.73 88.265 0)
      (effects (font (size 1.27 1.27)) (justify left bottom) hide)
    )
    (pin "1")
    (pin "2")
    (instances
      (project "data-center-rdimm-ddr4-tester"
        (path ""
          (reference "C42") (unit 1)
        )
      )
    )
  )

  (symbol (lib_id "antmicropower:GND") (at 156.21 73.025 0) (unit 1)
    (in_bom yes) (on_board yes) (dnp no) (fields_autoplaced)
    (property "Reference" "#PWR0154" (at 156.21 79.375 0)
      (effects (font (size 1.27 1.27)) hide)
    )
    (property "Value" "GND" (at 156.21 78.105 0)
      (effects (font (size 1.27 1.27)))
    )
    (property "Footprint" "" (at 156.21 73.025 0)
      (effects (font (size 1.27 1.27)) hide)
    )
    (property "Datasheet" "" (at 156.21 73.025 0)
      (effects (font (size 1.27 1.27)) hide)
    )
    (property "Author" "Antmicro" (at 165.1 80.645 0)
      (effects (font (size 1.27 1.27) (thickness 0.15)) (justify left bottom) hide)
    )
    (property "License" "Apache-2.0" (at 165.1 83.185 0)
      (effects (font (size 1.27 1.27) (thickness 0.15)) (justify left bottom) hide)
    )
    (pin "1")
    (instances
      (project "data-center-rdimm-ddr4-tester"
        (path ""
          (reference "#PWR0154") (unit 1)
        )
      )
    )
  )

  (symbol (lib_id "antmicroTestPoints:TP_1mm_SMD") (at 335.28 52.07 0) (unit 1)
    (in_bom yes) (on_board yes) (dnp no)
    (property "Reference" "TP8" (at 341.63 52.07 0)
      (effects (font (size 1.27 1.27)))
    )
    (property "Value" "TP_1mm_SMD" (at 350.52 59.69 0)
      (effects (font (size 1.27 1.27) (thickness 0.15)) (justify left bottom) hide)
    )
    (property "Footprint" "antmicro-footprints:TP_SMD_1mm" (at 350.52 62.23 0)
      (effects (font (size 1.27 1.27) (thickness 0.15)) (justify left bottom) hide)
    )
    (property "Datasheet" "" (at 350.52 64.77 0)
      (effects (font (size 1.27 1.27) (thickness 0.15)) (justify left bottom) hide)
    )
    (property "MPN" "" (at 335.28 52.07 0)
      (effects (font (size 1.27 1.27)) hide)
    )
    (property "Manufacturer" "" (at 335.28 52.07 0)
      (effects (font (size 1.27 1.27)) hide)
    )
    (property "Author" "Antmicro" (at 350.52 67.31 0)
      (effects (font (size 1.27 1.27) (thickness 0.15)) (justify left bottom) hide)
    )
    (property "License" "Apache-2.0" (at 350.52 69.85 0)
      (effects (font (size 1.27 1.27) (thickness 0.15)) (justify left bottom) hide)
    )
    (pin "1")
    (instances
      (project "data-center-rdimm-ddr4-tester"
        (path ""
          (reference "TP8") (unit 1)
        )
      )
    )
  )

  (symbol (lib_id "antmicroTestPoints:TP_1mm_SMD") (at 335.28 46.99 0) (unit 1)
    (in_bom yes) (on_board yes) (dnp no)
    (property "Reference" "TP7" (at 339.725 46.99 0)
      (effects (font (size 1.27 1.27)) (justify left))
    )
    (property "Value" "TP_1mm_SMD" (at 350.52 54.61 0)
      (effects (font (size 1.27 1.27) (thickness 0.15)) (justify left bottom) hide)
    )
    (property "Footprint" "antmicro-footprints:TP_SMD_1mm" (at 350.52 57.15 0)
      (effects (font (size 1.27 1.27) (thickness 0.15)) (justify left bottom) hide)
    )
    (property "Datasheet" "" (at 350.52 59.69 0)
      (effects (font (size 1.27 1.27) (thickness 0.15)) (justify left bottom) hide)
    )
    (property "MPN" "" (at 335.28 46.99 0)
      (effects (font (size 1.27 1.27)) hide)
    )
    (property "Manufacturer" "" (at 335.28 46.99 0)
      (effects (font (size 1.27 1.27)) hide)
    )
    (property "Author" "Antmicro" (at 350.52 62.23 0)
      (effects (font (size 1.27 1.27) (thickness 0.15)) (justify left bottom) hide)
    )
    (property "License" "Apache-2.0" (at 350.52 64.77 0)
      (effects (font (size 1.27 1.27) (thickness 0.15)) (justify left bottom) hide)
    )
    (pin "1")
    (instances
      (project "data-center-rdimm-ddr4-tester"
        (path ""
          (reference "TP7") (unit 1)
        )
      )
    )
  )

  (symbol (lib_id "antmicroTestPoints:TP_1mm_SMD") (at 335.28 41.91 0) (unit 1)
    (in_bom yes) (on_board yes) (dnp no)
    (property "Reference" "TP6" (at 341.63 41.91 0)
      (effects (font (size 1.27 1.27)))
    )
    (property "Value" "TP_1mm_SMD" (at 350.52 49.53 0)
      (effects (font (size 1.27 1.27) (thickness 0.15)) (justify left bottom) hide)
    )
    (property "Footprint" "antmicro-footprints:TP_SMD_1mm" (at 350.52 52.07 0)
      (effects (font (size 1.27 1.27) (thickness 0.15)) (justify left bottom) hide)
    )
    (property "Datasheet" "" (at 350.52 54.61 0)
      (effects (font (size 1.27 1.27) (thickness 0.15)) (justify left bottom) hide)
    )
    (property "MPN" "" (at 335.28 41.91 0)
      (effects (font (size 1.27 1.27)) hide)
    )
    (property "Manufacturer" "" (at 335.28 41.91 0)
      (effects (font (size 1.27 1.27)) hide)
    )
    (property "Author" "Antmicro" (at 350.52 57.15 0)
      (effects (font (size 1.27 1.27) (thickness 0.15)) (justify left bottom) hide)
    )
    (property "License" "Apache-2.0" (at 350.52 59.69 0)
      (effects (font (size 1.27 1.27) (thickness 0.15)) (justify left bottom) hide)
    )
    (pin "1")
    (instances
      (project "data-center-rdimm-ddr4-tester"
        (path ""
          (reference "TP6") (unit 1)
        )
      )
    )
  )

  (symbol (lib_id "antmicroResistors0402:R_0R_0402") (at 70.485 54.61 0) (unit 1)
    (in_bom yes) (on_board yes) (dnp no)
    (property "Reference" "R42" (at 68.58 53.34 0)
      (effects (font (size 1.524 1.524)))
    )
    (property "Value" "R_0R_0402" (at 90.805 67.31 0)
      (effects (font (size 1.27 1.27) (thickness 0.15)) (justify left bottom) hide)
    )
    (property "Footprint" "antmicro-footprints:R_0402_1005Metric" (at 90.805 69.85 0)
      (effects (font (size 1.27 1.27) (thickness 0.15)) (justify left bottom) hide)
    )
    (property "Datasheet" "https://industrial.panasonic.com/cdbs/www-data/pdf/RDA0000/AOA0000C301.pdf" (at 90.805 72.39 0)
      (effects (font (size 1.27 1.27) (thickness 0.15)) (justify left bottom) hide)
    )
    (property "Manufacturer" "Panasonic" (at 90.805 77.47 0)
      (effects (font (size 1.27 1.27) (thickness 0.15)) (justify left bottom) hide)
    )
    (property "MPN" "ERJ2GE0R00X" (at 90.805 74.93 0)
      (effects (font (size 1.27 1.27) (thickness 0.15)) (justify left bottom) hide)
    )
    (property "Val" "0R" (at 76.835 53.34 0)
      (effects (font (size 1.27 1.27) (thickness 0.15)))
    )
    (property "License" "Apache-2.0" (at 90.805 80.01 0)
      (effects (font (size 1.27 1.27) (thickness 0.15)) (justify left bottom) hide)
    )
    (property "Author" "Antmicro" (at 90.805 82.55 0)
      (effects (font (size 1.27 1.27) (thickness 0.15)) (justify left bottom) hide)
    )
    (property "Tolerance" "~" (at 90.805 64.77 0)
      (effects (font (size 1.27 1.27)) (justify left bottom) hide)
    )
    (property "Current" "1A" (at 90.805 85.09 0)
      (effects (font (size 1.27 1.27) (thickness 0.15)) (justify left bottom) hide)
    )
    (pin "1")
    (pin "2")
    (instances
      (project "data-center-rdimm-ddr4-tester"
        (path ""
          (reference "R42") (unit 1)
        )
      )
    )
  )

  (symbol (lib_id "antmicroCapacitors0402:C_10u_0402") (at 133.35 86.36 270) (unit 1)
    (in_bom yes) (on_board yes) (dnp no)
    (property "Reference" "C38" (at 133.985 86.995 90)
      (effects (font (size 1.524 1.524)) (justify left))
    )
    (property "Value" "C_10u_0402" (at 123.19 106.68 0)
      (effects (font (size 1.27 1.27) (thickness 0.15)) (justify left bottom) hide)
    )
    (property "Footprint" "antmicro-footprints:C_0402_1005Metric" (at 120.65 106.68 0)
      (effects (font (size 1.27 1.27) (thickness 0.15)) (justify left bottom) hide)
    )
    (property "Datasheet" " " (at 118.11 106.68 0)
      (effects (font (size 1.27 1.27) (thickness 0.15)) (justify left bottom) hide)
    )
    (property "Manufacturer" "Yaego" (at 113.03 106.68 0)
      (effects (font (size 1.27 1.27) (thickness 0.15)) (justify left bottom) hide)
    )
    (property "MPN" "CC0402MRX5R5BB106" (at 115.57 106.68 0)
      (effects (font (size 1.27 1.27) (thickness 0.15)) (justify left bottom) hide)
    )
    (property "Val" "10u" (at 133.985 90.805 90)
      (effects (font (size 1.27 1.27) (thickness 0.15)) (justify left))
    )
    (property "License" "Apache-2.0" (at 110.49 106.68 0)
      (effects (font (size 1.27 1.27) (thickness 0.15)) (justify left bottom) hide)
    )
    (property "Author" "Antmicro" (at 107.95 106.68 0)
      (effects (font (size 1.27 1.27) (thickness 0.15)) (justify left bottom) hide)
    )
    (property "Voltage" "" (at 105.41 106.68 0)
      (effects (font (size 1.27 1.27)) (justify left bottom) hide)
    )
    (property "Dielectric" "" (at 102.87 106.68 0)
      (effects (font (size 1.27 1.27)) (justify left bottom) hide)
    )
    (pin "1")
    (pin "2")
    (instances
      (project "data-center-rdimm-ddr4-tester"
        (path ""
          (reference "C38") (unit 1)
        )
      )
    )
  )

  (symbol (lib_id "antmicropower:GND") (at 133.35 91.44 0) (unit 1)
    (in_bom yes) (on_board yes) (dnp no) (fields_autoplaced)
    (property "Reference" "#PWR0156" (at 133.35 97.79 0)
      (effects (font (size 1.27 1.27)) hide)
    )
    (property "Value" "GND" (at 133.35 96.52 0)
      (effects (font (size 1.27 1.27)))
    )
    (property "Footprint" "" (at 133.35 91.44 0)
      (effects (font (size 1.27 1.27)) hide)
    )
    (property "Datasheet" "" (at 133.35 91.44 0)
      (effects (font (size 1.27 1.27)) hide)
    )
    (property "Author" "Antmicro" (at 142.24 99.06 0)
      (effects (font (size 1.27 1.27) (thickness 0.15)) (justify left bottom) hide)
    )
    (property "License" "Apache-2.0" (at 142.24 101.6 0)
      (effects (font (size 1.27 1.27) (thickness 0.15)) (justify left bottom) hide)
    )
    (pin "1")
    (instances
      (project "data-center-rdimm-ddr4-tester"
        (path ""
          (reference "#PWR0156") (unit 1)
        )
      )
    )
  )

  (symbol (lib_id "antmicroCapacitors0402:C_470n_0402") (at 74.295 64.77 270) (unit 1)
    (in_bom yes) (on_board yes) (dnp no) (fields_autoplaced)
    (property "Reference" "C36" (at 77.47 66.0463 90)
      (effects (font (size 1.524 1.524)) (justify left))
    )
    (property "Value" "C_470n_0402" (at 64.135 85.09 0)
      (effects (font (size 1.27 1.27) (thickness 0.15)) (justify left bottom) hide)
    )
    (property "Footprint" "antmicro-footprints:C_0402_1005Metric" (at 61.595 85.09 0)
      (effects (font (size 1.27 1.27) (thickness 0.15)) (justify left bottom) hide)
    )
    (property "Datasheet" " " (at 59.055 85.09 0)
      (effects (font (size 1.27 1.27) (thickness 0.15)) (justify left bottom) hide)
    )
    (property "Manufacturer" "TDK" (at 53.975 85.09 0)
      (effects (font (size 1.27 1.27) (thickness 0.15)) (justify left bottom) hide)
    )
    (property "MPN" "C1005X5R1E474M050BB" (at 56.515 85.09 0)
      (effects (font (size 1.27 1.27) (thickness 0.15)) (justify left bottom) hide)
    )
    (property "Val" "470n" (at 77.47 69.2212 90)
      (effects (font (size 1.27 1.27) (thickness 0.15)) (justify left))
    )
    (property "License" "Apache-2.0" (at 51.435 85.09 0)
      (effects (font (size 1.27 1.27) (thickness 0.15)) (justify left bottom) hide)
    )
    (property "Author" "Antmicro" (at 48.895 85.09 0)
      (effects (font (size 1.27 1.27) (thickness 0.15)) (justify left bottom) hide)
    )
    (property "Voltage" "" (at 46.355 85.09 0)
      (effects (font (size 1.27 1.27)) (justify left bottom) hide)
    )
    (property "Dielectric" "" (at 43.815 85.09 0)
      (effects (font (size 1.27 1.27)) (justify left bottom) hide)
    )
    (pin "1")
    (pin "2")
    (instances
      (project "data-center-rdimm-ddr4-tester"
        (path ""
          (reference "C36") (unit 1)
        )
      )
    )
  )

  (symbol (lib_id "antmicropower:GND") (at 67.945 72.39 0) (unit 1)
    (in_bom yes) (on_board yes) (dnp no) (fields_autoplaced)
    (property "Reference" "#PWR0157" (at 67.945 78.74 0)
      (effects (font (size 1.27 1.27)) hide)
    )
    (property "Value" "GND" (at 67.945 77.47 0)
      (effects (font (size 1.27 1.27)))
    )
    (property "Footprint" "" (at 67.945 72.39 0)
      (effects (font (size 1.27 1.27)) hide)
    )
    (property "Datasheet" "" (at 67.945 72.39 0)
      (effects (font (size 1.27 1.27)) hide)
    )
    (property "Author" "Antmicro" (at 76.835 80.01 0)
      (effects (font (size 1.27 1.27) (thickness 0.15)) (justify left bottom) hide)
    )
    (property "License" "Apache-2.0" (at 76.835 82.55 0)
      (effects (font (size 1.27 1.27) (thickness 0.15)) (justify left bottom) hide)
    )
    (pin "1")
    (instances
      (project "data-center-rdimm-ddr4-tester"
        (path ""
          (reference "#PWR0157") (unit 1)
        )
      )
    )
  )

  (symbol (lib_id "antmicropower:GND") (at 74.295 72.39 0) (unit 1)
    (in_bom yes) (on_board yes) (dnp no) (fields_autoplaced)
    (property "Reference" "#PWR0158" (at 74.295 78.74 0)
      (effects (font (size 1.27 1.27)) hide)
    )
    (property "Value" "GND" (at 74.295 77.47 0)
      (effects (font (size 1.27 1.27)))
    )
    (property "Footprint" "" (at 74.295 72.39 0)
      (effects (font (size 1.27 1.27)) hide)
    )
    (property "Datasheet" "" (at 74.295 72.39 0)
      (effects (font (size 1.27 1.27)) hide)
    )
    (property "Author" "Antmicro" (at 83.185 80.01 0)
      (effects (font (size 1.27 1.27) (thickness 0.15)) (justify left bottom) hide)
    )
    (property "License" "Apache-2.0" (at 83.185 82.55 0)
      (effects (font (size 1.27 1.27) (thickness 0.15)) (justify left bottom) hide)
    )
    (pin "1")
    (instances
      (project "data-center-rdimm-ddr4-tester"
        (path ""
          (reference "#PWR0158") (unit 1)
        )
      )
    )
  )

  (symbol (lib_id "antmicroCapacitors0603:C_10u_25V_0603") (at 132.715 28.575 270) (unit 1)
    (in_bom yes) (on_board yes) (dnp no)
    (property "Reference" "C27" (at 133.35 29.21 90)
      (effects (font (size 1.524 1.524)) (justify left))
    )
    (property "Value" "C_10u_25V_0603" (at 122.555 48.895 0)
      (effects (font (size 1.27 1.27) (thickness 0.15)) (justify left bottom) hide)
    )
    (property "Footprint" "antmicro-footprints:C_0603_1608Metric" (at 120.015 48.895 0)
      (effects (font (size 1.27 1.27) (thickness 0.15)) (justify left bottom) hide)
    )
    (property "Datasheet" " " (at 117.475 48.895 0)
      (effects (font (size 1.27 1.27) (thickness 0.15)) (justify left bottom) hide)
    )
    (property "Manufacturer" "TDK" (at 112.395 48.895 0)
      (effects (font (size 1.27 1.27) (thickness 0.15)) (justify left bottom) hide)
    )
    (property "MPN" "C1608X5R1E106M080AC" (at 114.935 48.895 0)
      (effects (font (size 1.27 1.27) (thickness 0.15)) (justify left bottom) hide)
    )
    (property "Val" "10u/25V" (at 133.35 33.02 90)
      (effects (font (size 1.27 1.27) (thickness 0.15)) (justify left))
    )
    (property "License" "Apache-2.0" (at 109.855 48.895 0)
      (effects (font (size 1.27 1.27) (thickness 0.15)) (justify left bottom) hide)
    )
    (property "Author" "Antmicro" (at 107.315 48.895 0)
      (effects (font (size 1.27 1.27) (thickness 0.15)) (justify left bottom) hide)
    )
    (property "Voltage" "" (at 104.775 48.895 0)
      (effects (font (size 1.27 1.27)) (justify left bottom) hide)
    )
    (property "Dielectric" "" (at 102.235 48.895 0)
      (effects (font (size 1.27 1.27)) (justify left bottom) hide)
    )
    (pin "1")
    (pin "2")
    (instances
      (project "data-center-rdimm-ddr4-tester"
        (path ""
          (reference "C27") (unit 1)
        )
      )
    )
  )

  (symbol (lib_id "antmicropower:GND") (at 385.445 242.57 0) (unit 1)
    (in_bom yes) (on_board yes) (dnp no) (fields_autoplaced)
    (property "Reference" "#PWR036" (at 385.445 248.92 0)
      (effects (font (size 1.27 1.27)) hide)
    )
    (property "Value" "GND" (at 385.445 247.015 0)
      (effects (font (size 1.27 1.27)))
    )
    (property "Footprint" "" (at 385.445 242.57 0)
      (effects (font (size 1.27 1.27)) hide)
    )
    (property "Datasheet" "" (at 385.445 242.57 0)
      (effects (font (size 1.27 1.27)) hide)
    )
    (property "Author" "Antmicro" (at 394.335 250.19 0)
      (effects (font (size 1.27 1.27) (thickness 0.15)) (justify left bottom) hide)
    )
    (property "License" "Apache-2.0" (at 394.335 252.73 0)
      (effects (font (size 1.27 1.27) (thickness 0.15)) (justify left bottom) hide)
    )
    (pin "1")
    (instances
      (project "data-center-rdimm-ddr4-tester"
        (path ""
          (reference "#PWR036") (unit 1)
        )
      )
    )
  )

  (symbol (lib_id "antmicroCapacitors0603:C_10n_0603") (at 29.845 89.535 270) (unit 1)
    (in_bom yes) (on_board yes) (dnp no)
    (property "Reference" "C106" (at 30.48 90.17 90)
      (effects (font (size 1.524 1.524)) (justify left))
    )
    (property "Value" "C_10n_0603" (at 19.685 109.855 0)
      (effects (font (size 1.27 1.27) (thickness 0.15)) (justify left bottom) hide)
    )
    (property "Footprint" "antmicro-footprints:C_0603_1608Metric" (at 17.145 109.855 0)
      (effects (font (size 1.27 1.27) (thickness 0.15)) (justify left bottom) hide)
    )
    (property "Datasheet" " " (at 14.605 109.855 0)
      (effects (font (size 1.27 1.27) (thickness 0.15)) (justify left bottom) hide)
    )
    (property "Manufacturer" "AVX" (at 9.525 109.855 0)
      (effects (font (size 1.27 1.27) (thickness 0.15)) (justify left bottom) hide)
    )
    (property "MPN" "06031C103JAT2A" (at 12.065 109.855 0)
      (effects (font (size 1.27 1.27) (thickness 0.15)) (justify left bottom) hide)
    )
    (property "Val" "10n" (at 30.48 93.98 90)
      (effects (font (size 1.27 1.27) (thickness 0.15)) (justify left))
    )
    (property "License" "Apache-2.0" (at 6.985 109.855 0)
      (effects (font (size 1.27 1.27) (thickness 0.15)) (justify left bottom) hide)
    )
    (property "Author" "Antmicro" (at 4.445 109.855 0)
      (effects (font (size 1.27 1.27) (thickness 0.15)) (justify left bottom) hide)
    )
    (property "Voltage" "" (at 1.905 109.855 0)
      (effects (font (size 1.27 1.27)) (justify left bottom) hide)
    )
    (property "Dielectric" "" (at -0.635 109.855 0)
      (effects (font (size 1.27 1.27)) (justify left bottom) hide)
    )
    (pin "1")
    (pin "2")
    (instances
      (project "data-center-rdimm-ddr4-tester"
        (path ""
          (reference "C106") (unit 1)
        )
      )
    )
  )

  (symbol (lib_id "antmicropower:GND") (at 29.845 94.615 0) (unit 1)
    (in_bom yes) (on_board yes) (dnp no) (fields_autoplaced)
    (property "Reference" "#PWR025" (at 29.845 100.965 0)
      (effects (font (size 1.27 1.27)) hide)
    )
    (property "Value" "GND" (at 29.845 99.695 0)
      (effects (font (size 1.27 1.27)))
    )
    (property "Footprint" "" (at 29.845 94.615 0)
      (effects (font (size 1.27 1.27)) hide)
    )
    (property "Datasheet" "" (at 29.845 94.615 0)
      (effects (font (size 1.27 1.27)) hide)
    )
    (property "Author" "Antmicro" (at 38.735 102.235 0)
      (effects (font (size 1.27 1.27) (thickness 0.15)) (justify left bottom) hide)
    )
    (property "License" "Apache-2.0" (at 38.735 104.775 0)
      (effects (font (size 1.27 1.27) (thickness 0.15)) (justify left bottom) hide)
    )
    (pin "1")
    (instances
      (project "data-center-rdimm-ddr4-tester"
        (path ""
          (reference "#PWR025") (unit 1)
        )
      )
    )
  )

  (symbol (lib_id "antmicroCapacitors0603:C_10n_0603") (at 38.1 89.535 270) (unit 1)
    (in_bom yes) (on_board yes) (dnp no)
    (property "Reference" "C107" (at 38.735 90.17 90)
      (effects (font (size 1.524 1.524)) (justify left))
    )
    (property "Value" "C_10n_0603" (at 27.94 109.855 0)
      (effects (font (size 1.27 1.27) (thickness 0.15)) (justify left bottom) hide)
    )
    (property "Footprint" "antmicro-footprints:C_0603_1608Metric" (at 25.4 109.855 0)
      (effects (font (size 1.27 1.27) (thickness 0.15)) (justify left bottom) hide)
    )
    (property "Datasheet" " " (at 22.86 109.855 0)
      (effects (font (size 1.27 1.27) (thickness 0.15)) (justify left bottom) hide)
    )
    (property "Manufacturer" "AVX" (at 17.78 109.855 0)
      (effects (font (size 1.27 1.27) (thickness 0.15)) (justify left bottom) hide)
    )
    (property "MPN" "06031C103JAT2A" (at 20.32 109.855 0)
      (effects (font (size 1.27 1.27) (thickness 0.15)) (justify left bottom) hide)
    )
    (property "Val" "10n" (at 38.735 93.98 90)
      (effects (font (size 1.27 1.27) (thickness 0.15)) (justify left))
    )
    (property "License" "Apache-2.0" (at 15.24 109.855 0)
      (effects (font (size 1.27 1.27) (thickness 0.15)) (justify left bottom) hide)
    )
    (property "Author" "Antmicro" (at 12.7 109.855 0)
      (effects (font (size 1.27 1.27) (thickness 0.15)) (justify left bottom) hide)
    )
    (property "Voltage" "" (at 10.16 109.855 0)
      (effects (font (size 1.27 1.27)) (justify left bottom) hide)
    )
    (property "Dielectric" "" (at 7.62 109.855 0)
      (effects (font (size 1.27 1.27)) (justify left bottom) hide)
    )
    (pin "1")
    (pin "2")
    (instances
      (project "data-center-rdimm-ddr4-tester"
        (path ""
          (reference "C107") (unit 1)
        )
      )
    )
  )

  (symbol (lib_id "antmicropower:GND") (at 38.1 94.615 0) (unit 1)
    (in_bom yes) (on_board yes) (dnp no) (fields_autoplaced)
    (property "Reference" "#PWR026" (at 38.1 100.965 0)
      (effects (font (size 1.27 1.27)) hide)
    )
    (property "Value" "GND" (at 38.1 99.695 0)
      (effects (font (size 1.27 1.27)))
    )
    (property "Footprint" "" (at 38.1 94.615 0)
      (effects (font (size 1.27 1.27)) hide)
    )
    (property "Datasheet" "" (at 38.1 94.615 0)
      (effects (font (size 1.27 1.27)) hide)
    )
    (property "Author" "Antmicro" (at 46.99 102.235 0)
      (effects (font (size 1.27 1.27) (thickness 0.15)) (justify left bottom) hide)
    )
    (property "License" "Apache-2.0" (at 46.99 104.775 0)
      (effects (font (size 1.27 1.27) (thickness 0.15)) (justify left bottom) hide)
    )
    (pin "1")
    (instances
      (project "data-center-rdimm-ddr4-tester"
        (path ""
          (reference "#PWR026") (unit 1)
        )
      )
    )
  )

  (symbol (lib_id "antmicroCapacitors0603:C_10n_0603") (at 46.355 89.535 270) (unit 1)
    (in_bom yes) (on_board yes) (dnp no)
    (property "Reference" "C108" (at 46.99 90.17 90)
      (effects (font (size 1.524 1.524)) (justify left))
    )
    (property "Value" "C_10n_0603" (at 36.195 109.855 0)
      (effects (font (size 1.27 1.27) (thickness 0.15)) (justify left bottom) hide)
    )
    (property "Footprint" "antmicro-footprints:C_0603_1608Metric" (at 33.655 109.855 0)
      (effects (font (size 1.27 1.27) (thickness 0.15)) (justify left bottom) hide)
    )
    (property "Datasheet" " " (at 31.115 109.855 0)
      (effects (font (size 1.27 1.27) (thickness 0.15)) (justify left bottom) hide)
    )
    (property "Manufacturer" "AVX" (at 26.035 109.855 0)
      (effects (font (size 1.27 1.27) (thickness 0.15)) (justify left bottom) hide)
    )
    (property "MPN" "06031C103JAT2A" (at 28.575 109.855 0)
      (effects (font (size 1.27 1.27) (thickness 0.15)) (justify left bottom) hide)
    )
    (property "Val" "10n" (at 46.99 93.98 90)
      (effects (font (size 1.27 1.27) (thickness 0.15)) (justify left))
    )
    (property "License" "Apache-2.0" (at 23.495 109.855 0)
      (effects (font (size 1.27 1.27) (thickness 0.15)) (justify left bottom) hide)
    )
    (property "Author" "Antmicro" (at 20.955 109.855 0)
      (effects (font (size 1.27 1.27) (thickness 0.15)) (justify left bottom) hide)
    )
    (property "Voltage" "" (at 18.415 109.855 0)
      (effects (font (size 1.27 1.27)) (justify left bottom) hide)
    )
    (property "Dielectric" "" (at 15.875 109.855 0)
      (effects (font (size 1.27 1.27)) (justify left bottom) hide)
    )
    (pin "1")
    (pin "2")
    (instances
      (project "data-center-rdimm-ddr4-tester"
        (path ""
          (reference "C108") (unit 1)
        )
      )
    )
  )

  (symbol (lib_id "antmicropower:GND") (at 46.355 94.615 0) (unit 1)
    (in_bom yes) (on_board yes) (dnp no) (fields_autoplaced)
    (property "Reference" "#PWR027" (at 46.355 100.965 0)
      (effects (font (size 1.27 1.27)) hide)
    )
    (property "Value" "GND" (at 46.355 99.695 0)
      (effects (font (size 1.27 1.27)))
    )
    (property "Footprint" "" (at 46.355 94.615 0)
      (effects (font (size 1.27 1.27)) hide)
    )
    (property "Datasheet" "" (at 46.355 94.615 0)
      (effects (font (size 1.27 1.27)) hide)
    )
    (property "Author" "Antmicro" (at 55.245 102.235 0)
      (effects (font (size 1.27 1.27) (thickness 0.15)) (justify left bottom) hide)
    )
    (property "License" "Apache-2.0" (at 55.245 104.775 0)
      (effects (font (size 1.27 1.27) (thickness 0.15)) (justify left bottom) hide)
    )
    (pin "1")
    (instances
      (project "data-center-rdimm-ddr4-tester"
        (path ""
          (reference "#PWR027") (unit 1)
        )
      )
    )
  )

  (symbol (lib_id "antmicroCapacitors0603:C_10n_0603") (at 54.61 89.535 270) (unit 1)
    (in_bom yes) (on_board yes) (dnp no)
    (property "Reference" "C109" (at 55.245 90.17 90)
      (effects (font (size 1.524 1.524)) (justify left))
    )
    (property "Value" "C_10n_0603" (at 44.45 109.855 0)
      (effects (font (size 1.27 1.27) (thickness 0.15)) (justify left bottom) hide)
    )
    (property "Footprint" "antmicro-footprints:C_0603_1608Metric" (at 41.91 109.855 0)
      (effects (font (size 1.27 1.27) (thickness 0.15)) (justify left bottom) hide)
    )
    (property "Datasheet" " " (at 39.37 109.855 0)
      (effects (font (size 1.27 1.27) (thickness 0.15)) (justify left bottom) hide)
    )
    (property "Manufacturer" "AVX" (at 34.29 109.855 0)
      (effects (font (size 1.27 1.27) (thickness 0.15)) (justify left bottom) hide)
    )
    (property "MPN" "06031C103JAT2A" (at 36.83 109.855 0)
      (effects (font (size 1.27 1.27) (thickness 0.15)) (justify left bottom) hide)
    )
    (property "Val" "10n" (at 55.245 93.98 90)
      (effects (font (size 1.27 1.27) (thickness 0.15)) (justify left))
    )
    (property "License" "Apache-2.0" (at 31.75 109.855 0)
      (effects (font (size 1.27 1.27) (thickness 0.15)) (justify left bottom) hide)
    )
    (property "Author" "Antmicro" (at 29.21 109.855 0)
      (effects (font (size 1.27 1.27) (thickness 0.15)) (justify left bottom) hide)
    )
    (property "Voltage" "" (at 26.67 109.855 0)
      (effects (font (size 1.27 1.27)) (justify left bottom) hide)
    )
    (property "Dielectric" "" (at 24.13 109.855 0)
      (effects (font (size 1.27 1.27)) (justify left bottom) hide)
    )
    (pin "1")
    (pin "2")
    (instances
      (project "data-center-rdimm-ddr4-tester"
        (path ""
          (reference "C109") (unit 1)
        )
      )
    )
  )

  (symbol (lib_id "antmicropower:GND") (at 54.61 94.615 0) (unit 1)
    (in_bom yes) (on_board yes) (dnp no) (fields_autoplaced)
    (property "Reference" "#PWR028" (at 54.61 100.965 0)
      (effects (font (size 1.27 1.27)) hide)
    )
    (property "Value" "GND" (at 54.61 99.695 0)
      (effects (font (size 1.27 1.27)))
    )
    (property "Footprint" "" (at 54.61 94.615 0)
      (effects (font (size 1.27 1.27)) hide)
    )
    (property "Datasheet" "" (at 54.61 94.615 0)
      (effects (font (size 1.27 1.27)) hide)
    )
    (property "Author" "Antmicro" (at 63.5 102.235 0)
      (effects (font (size 1.27 1.27) (thickness 0.15)) (justify left bottom) hide)
    )
    (property "License" "Apache-2.0" (at 63.5 104.775 0)
      (effects (font (size 1.27 1.27) (thickness 0.15)) (justify left bottom) hide)
    )
    (pin "1")
    (instances
      (project "data-center-rdimm-ddr4-tester"
        (path ""
          (reference "#PWR028") (unit 1)
        )
      )
    )
  )

  (symbol (lib_id "antmicroCapacitors0603:C_10u_25V_0603") (at 143.51 28.575 270) (unit 1)
    (in_bom yes) (on_board yes) (dnp no)
    (property "Reference" "C28" (at 144.145 29.21 90)
      (effects (font (size 1.524 1.524)) (justify left))
    )
    (property "Value" "C_10u_25V_0603" (at 133.35 48.895 0)
      (effects (font (size 1.27 1.27) (thickness 0.15)) (justify left bottom) hide)
    )
    (property "Footprint" "antmicro-footprints:C_0603_1608Metric" (at 130.81 48.895 0)
      (effects (font (size 1.27 1.27) (thickness 0.15)) (justify left bottom) hide)
    )
    (property "Datasheet" " " (at 128.27 48.895 0)
      (effects (font (size 1.27 1.27) (thickness 0.15)) (justify left bottom) hide)
    )
    (property "Manufacturer" "TDK" (at 123.19 48.895 0)
      (effects (font (size 1.27 1.27) (thickness 0.15)) (justify left bottom) hide)
    )
    (property "MPN" "C1608X5R1E106M080AC" (at 125.73 48.895 0)
      (effects (font (size 1.27 1.27) (thickness 0.15)) (justify left bottom) hide)
    )
    (property "Val" "10u/25V" (at 144.145 33.02 90)
      (effects (font (size 1.27 1.27) (thickness 0.15)) (justify left))
    )
    (property "License" "Apache-2.0" (at 120.65 48.895 0)
      (effects (font (size 1.27 1.27) (thickness 0.15)) (justify left bottom) hide)
    )
    (property "Author" "Antmicro" (at 118.11 48.895 0)
      (effects (font (size 1.27 1.27) (thickness 0.15)) (justify left bottom) hide)
    )
    (property "Voltage" "" (at 115.57 48.895 0)
      (effects (font (size 1.27 1.27)) (justify left bottom) hide)
    )
    (property "Dielectric" "" (at 113.03 48.895 0)
      (effects (font (size 1.27 1.27)) (justify left bottom) hide)
    )
    (pin "1")
    (pin "2")
    (instances
      (project "data-center-rdimm-ddr4-tester"
        (path ""
          (reference "C28") (unit 1)
        )
      )
    )
  )

  (symbol (lib_id "antmicroCapacitors0603:C_10u_25V_0603") (at 154.305 28.575 270) (unit 1)
    (in_bom yes) (on_board yes) (dnp no)
    (property "Reference" "C29" (at 154.94 29.21 90)
      (effects (font (size 1.524 1.524)) (justify left))
    )
    (property "Value" "C_10u_25V_0603" (at 144.145 48.895 0)
      (effects (font (size 1.27 1.27) (thickness 0.15)) (justify left bottom) hide)
    )
    (property "Footprint" "antmicro-footprints:C_0603_1608Metric" (at 141.605 48.895 0)
      (effects (font (size 1.27 1.27) (thickness 0.15)) (justify left bottom) hide)
    )
    (property "Datasheet" " " (at 139.065 48.895 0)
      (effects (font (size 1.27 1.27) (thickness 0.15)) (justify left bottom) hide)
    )
    (property "Manufacturer" "TDK" (at 133.985 48.895 0)
      (effects (font (size 1.27 1.27) (thickness 0.15)) (justify left bottom) hide)
    )
    (property "MPN" "C1608X5R1E106M080AC" (at 136.525 48.895 0)
      (effects (font (size 1.27 1.27) (thickness 0.15)) (justify left bottom) hide)
    )
    (property "Val" "10u/25V" (at 154.94 33.02 90)
      (effects (font (size 1.27 1.27) (thickness 0.15)) (justify left))
    )
    (property "License" "Apache-2.0" (at 131.445 48.895 0)
      (effects (font (size 1.27 1.27) (thickness 0.15)) (justify left bottom) hide)
    )
    (property "Author" "Antmicro" (at 128.905 48.895 0)
      (effects (font (size 1.27 1.27) (thickness 0.15)) (justify left bottom) hide)
    )
    (property "Voltage" "" (at 126.365 48.895 0)
      (effects (font (size 1.27 1.27)) (justify left bottom) hide)
    )
    (property "Dielectric" "" (at 123.825 48.895 0)
      (effects (font (size 1.27 1.27)) (justify left bottom) hide)
    )
    (pin "1")
    (pin "2")
    (instances
      (project "data-center-rdimm-ddr4-tester"
        (path ""
          (reference "C29") (unit 1)
        )
      )
    )
  )

  (symbol (lib_id "antmicropower:GND") (at 143.51 33.655 0) (unit 1)
    (in_bom yes) (on_board yes) (dnp no) (fields_autoplaced)
    (property "Reference" "#PWR0159" (at 143.51 40.005 0)
      (effects (font (size 1.27 1.27)) hide)
    )
    (property "Value" "GND" (at 143.51 38.735 0)
      (effects (font (size 1.27 1.27)))
    )
    (property "Footprint" "" (at 143.51 33.655 0)
      (effects (font (size 1.27 1.27)) hide)
    )
    (property "Datasheet" "" (at 143.51 33.655 0)
      (effects (font (size 1.27 1.27)) hide)
    )
    (property "Author" "Antmicro" (at 152.4 41.275 0)
      (effects (font (size 1.27 1.27) (thickness 0.15)) (justify left bottom) hide)
    )
    (property "License" "Apache-2.0" (at 152.4 43.815 0)
      (effects (font (size 1.27 1.27) (thickness 0.15)) (justify left bottom) hide)
    )
    (pin "1")
    (instances
      (project "data-center-rdimm-ddr4-tester"
        (path ""
          (reference "#PWR0159") (unit 1)
        )
      )
    )
  )

  (symbol (lib_id "antmicropower:GND") (at 154.305 33.655 0) (unit 1)
    (in_bom yes) (on_board yes) (dnp no) (fields_autoplaced)
    (property "Reference" "#PWR0160" (at 154.305 40.005 0)
      (effects (font (size 1.27 1.27)) hide)
    )
    (property "Value" "GND" (at 154.305 38.735 0)
      (effects (font (size 1.27 1.27)))
    )
    (property "Footprint" "" (at 154.305 33.655 0)
      (effects (font (size 1.27 1.27)) hide)
    )
    (property "Datasheet" "" (at 154.305 33.655 0)
      (effects (font (size 1.27 1.27)) hide)
    )
    (property "Author" "Antmicro" (at 163.195 41.275 0)
      (effects (font (size 1.27 1.27) (thickness 0.15)) (justify left bottom) hide)
    )
    (property "License" "Apache-2.0" (at 163.195 43.815 0)
      (effects (font (size 1.27 1.27) (thickness 0.15)) (justify left bottom) hide)
    )
    (pin "1")
    (instances
      (project "data-center-rdimm-ddr4-tester"
        (path ""
          (reference "#PWR0160") (unit 1)
        )
      )
    )
  )

  (symbol (lib_id "antmicropower:GND") (at 165.1 33.655 0) (unit 1)
    (in_bom yes) (on_board yes) (dnp no) (fields_autoplaced)
    (property "Reference" "#PWR0161" (at 165.1 40.005 0)
      (effects (font (size 1.27 1.27)) hide)
    )
    (property "Value" "GND" (at 165.1 38.735 0)
      (effects (font (size 1.27 1.27)))
    )
    (property "Footprint" "" (at 165.1 33.655 0)
      (effects (font (size 1.27 1.27)) hide)
    )
    (property "Datasheet" "" (at 165.1 33.655 0)
      (effects (font (size 1.27 1.27)) hide)
    )
    (property "Author" "Antmicro" (at 173.99 41.275 0)
      (effects (font (size 1.27 1.27) (thickness 0.15)) (justify left bottom) hide)
    )
    (property "License" "Apache-2.0" (at 173.99 43.815 0)
      (effects (font (size 1.27 1.27) (thickness 0.15)) (justify left bottom) hide)
    )
    (pin "1")
    (instances
      (project "data-center-rdimm-ddr4-tester"
        (path ""
          (reference "#PWR0161") (unit 1)
        )
      )
    )
  )

  (symbol (lib_id "antmicroCapacitors0603:C_10n_0603") (at 72.39 89.535 270) (unit 1)
    (in_bom yes) (on_board yes) (dnp no)
    (property "Reference" "C110" (at 73.025 90.17 90)
      (effects (font (size 1.524 1.524)) (justify left))
    )
    (property "Value" "C_10n_0603" (at 62.23 109.855 0)
      (effects (font (size 1.27 1.27) (thickness 0.15)) (justify left bottom) hide)
    )
    (property "Footprint" "antmicro-footprints:C_0603_1608Metric" (at 59.69 109.855 0)
      (effects (font (size 1.27 1.27) (thickness 0.15)) (justify left bottom) hide)
    )
    (property "Datasheet" " " (at 57.15 109.855 0)
      (effects (font (size 1.27 1.27) (thickness 0.15)) (justify left bottom) hide)
    )
    (property "Manufacturer" "AVX" (at 52.07 109.855 0)
      (effects (font (size 1.27 1.27) (thickness 0.15)) (justify left bottom) hide)
    )
    (property "MPN" "06031C103JAT2A" (at 54.61 109.855 0)
      (effects (font (size 1.27 1.27) (thickness 0.15)) (justify left bottom) hide)
    )
    (property "Val" "10n" (at 73.025 93.98 90)
      (effects (font (size 1.27 1.27) (thickness 0.15)) (justify left))
    )
    (property "License" "Apache-2.0" (at 49.53 109.855 0)
      (effects (font (size 1.27 1.27) (thickness 0.15)) (justify left bottom) hide)
    )
    (property "Author" "Antmicro" (at 46.99 109.855 0)
      (effects (font (size 1.27 1.27) (thickness 0.15)) (justify left bottom) hide)
    )
    (property "Voltage" "" (at 44.45 109.855 0)
      (effects (font (size 1.27 1.27)) (justify left bottom) hide)
    )
    (property "Dielectric" "" (at 41.91 109.855 0)
      (effects (font (size 1.27 1.27)) (justify left bottom) hide)
    )
    (pin "1")
    (pin "2")
    (instances
      (project "data-center-rdimm-ddr4-tester"
        (path ""
          (reference "C110") (unit 1)
        )
      )
    )
  )

  (symbol (lib_id "antmicropower:GND") (at 72.39 94.615 0) (unit 1)
    (in_bom yes) (on_board yes) (dnp no) (fields_autoplaced)
    (property "Reference" "#PWR029" (at 72.39 100.965 0)
      (effects (font (size 1.27 1.27)) hide)
    )
    (property "Value" "GND" (at 72.39 99.695 0)
      (effects (font (size 1.27 1.27)))
    )
    (property "Footprint" "" (at 72.39 94.615 0)
      (effects (font (size 1.27 1.27)) hide)
    )
    (property "Datasheet" "" (at 72.39 94.615 0)
      (effects (font (size 1.27 1.27)) hide)
    )
    (property "Author" "Antmicro" (at 81.28 102.235 0)
      (effects (font (size 1.27 1.27) (thickness 0.15)) (justify left bottom) hide)
    )
    (property "License" "Apache-2.0" (at 81.28 104.775 0)
      (effects (font (size 1.27 1.27) (thickness 0.15)) (justify left bottom) hide)
    )
    (pin "1")
    (instances
      (project "data-center-rdimm-ddr4-tester"
        (path ""
          (reference "#PWR029") (unit 1)
        )
      )
    )
  )

  (symbol (lib_id "antmicroCapacitors0603:C_10n_0603") (at 80.645 89.535 270) (unit 1)
    (in_bom yes) (on_board yes) (dnp no)
    (property "Reference" "C111" (at 81.28 90.17 90)
      (effects (font (size 1.524 1.524)) (justify left))
    )
    (property "Value" "C_10n_0603" (at 70.485 109.855 0)
      (effects (font (size 1.27 1.27) (thickness 0.15)) (justify left bottom) hide)
    )
    (property "Footprint" "antmicro-footprints:C_0603_1608Metric" (at 67.945 109.855 0)
      (effects (font (size 1.27 1.27) (thickness 0.15)) (justify left bottom) hide)
    )
    (property "Datasheet" " " (at 65.405 109.855 0)
      (effects (font (size 1.27 1.27) (thickness 0.15)) (justify left bottom) hide)
    )
    (property "Manufacturer" "AVX" (at 60.325 109.855 0)
      (effects (font (size 1.27 1.27) (thickness 0.15)) (justify left bottom) hide)
    )
    (property "MPN" "06031C103JAT2A" (at 62.865 109.855 0)
      (effects (font (size 1.27 1.27) (thickness 0.15)) (justify left bottom) hide)
    )
    (property "Val" "10n" (at 81.28 93.98 90)
      (effects (font (size 1.27 1.27) (thickness 0.15)) (justify left))
    )
    (property "License" "Apache-2.0" (at 57.785 109.855 0)
      (effects (font (size 1.27 1.27) (thickness 0.15)) (justify left bottom) hide)
    )
    (property "Author" "Antmicro" (at 55.245 109.855 0)
      (effects (font (size 1.27 1.27) (thickness 0.15)) (justify left bottom) hide)
    )
    (property "Voltage" "" (at 52.705 109.855 0)
      (effects (font (size 1.27 1.27)) (justify left bottom) hide)
    )
    (property "Dielectric" "" (at 50.165 109.855 0)
      (effects (font (size 1.27 1.27)) (justify left bottom) hide)
    )
    (pin "1")
    (pin "2")
    (instances
      (project "data-center-rdimm-ddr4-tester"
        (path ""
          (reference "C111") (unit 1)
        )
      )
    )
  )

  (symbol (lib_id "antmicropower:GND") (at 80.645 94.615 0) (unit 1)
    (in_bom yes) (on_board yes) (dnp no) (fields_autoplaced)
    (property "Reference" "#PWR030" (at 80.645 100.965 0)
      (effects (font (size 1.27 1.27)) hide)
    )
    (property "Value" "GND" (at 80.645 99.695 0)
      (effects (font (size 1.27 1.27)))
    )
    (property "Footprint" "" (at 80.645 94.615 0)
      (effects (font (size 1.27 1.27)) hide)
    )
    (property "Datasheet" "" (at 80.645 94.615 0)
      (effects (font (size 1.27 1.27)) hide)
    )
    (property "Author" "Antmicro" (at 89.535 102.235 0)
      (effects (font (size 1.27 1.27) (thickness 0.15)) (justify left bottom) hide)
    )
    (property "License" "Apache-2.0" (at 89.535 104.775 0)
      (effects (font (size 1.27 1.27) (thickness 0.15)) (justify left bottom) hide)
    )
    (pin "1")
    (instances
      (project "data-center-rdimm-ddr4-tester"
        (path ""
          (reference "#PWR030") (unit 1)
        )
      )
    )
  )

  (symbol (lib_id "antmicroCapacitors0603:C_10n_0603") (at 88.9 89.535 270) (unit 1)
    (in_bom yes) (on_board yes) (dnp no)
    (property "Reference" "C112" (at 89.535 90.17 90)
      (effects (font (size 1.524 1.524)) (justify left))
    )
    (property "Value" "C_10n_0603" (at 78.74 109.855 0)
      (effects (font (size 1.27 1.27) (thickness 0.15)) (justify left bottom) hide)
    )
    (property "Footprint" "antmicro-footprints:C_0603_1608Metric" (at 76.2 109.855 0)
      (effects (font (size 1.27 1.27) (thickness 0.15)) (justify left bottom) hide)
    )
    (property "Datasheet" " " (at 73.66 109.855 0)
      (effects (font (size 1.27 1.27) (thickness 0.15)) (justify left bottom) hide)
    )
    (property "Manufacturer" "AVX" (at 68.58 109.855 0)
      (effects (font (size 1.27 1.27) (thickness 0.15)) (justify left bottom) hide)
    )
    (property "MPN" "06031C103JAT2A" (at 71.12 109.855 0)
      (effects (font (size 1.27 1.27) (thickness 0.15)) (justify left bottom) hide)
    )
    (property "Val" "10n" (at 89.535 93.98 90)
      (effects (font (size 1.27 1.27) (thickness 0.15)) (justify left))
    )
    (property "License" "Apache-2.0" (at 66.04 109.855 0)
      (effects (font (size 1.27 1.27) (thickness 0.15)) (justify left bottom) hide)
    )
    (property "Author" "Antmicro" (at 63.5 109.855 0)
      (effects (font (size 1.27 1.27) (thickness 0.15)) (justify left bottom) hide)
    )
    (property "Voltage" "" (at 60.96 109.855 0)
      (effects (font (size 1.27 1.27)) (justify left bottom) hide)
    )
    (property "Dielectric" "" (at 58.42 109.855 0)
      (effects (font (size 1.27 1.27)) (justify left bottom) hide)
    )
    (pin "1")
    (pin "2")
    (instances
      (project "data-center-rdimm-ddr4-tester"
        (path ""
          (reference "C112") (unit 1)
        )
      )
    )
  )

  (symbol (lib_id "antmicropower:GND") (at 88.9 94.615 0) (unit 1)
    (in_bom yes) (on_board yes) (dnp no) (fields_autoplaced)
    (property "Reference" "#PWR031" (at 88.9 100.965 0)
      (effects (font (size 1.27 1.27)) hide)
    )
    (property "Value" "GND" (at 88.9 99.695 0)
      (effects (font (size 1.27 1.27)))
    )
    (property "Footprint" "" (at 88.9 94.615 0)
      (effects (font (size 1.27 1.27)) hide)
    )
    (property "Datasheet" "" (at 88.9 94.615 0)
      (effects (font (size 1.27 1.27)) hide)
    )
    (property "Author" "Antmicro" (at 97.79 102.235 0)
      (effects (font (size 1.27 1.27) (thickness 0.15)) (justify left bottom) hide)
    )
    (property "License" "Apache-2.0" (at 97.79 104.775 0)
      (effects (font (size 1.27 1.27) (thickness 0.15)) (justify left bottom) hide)
    )
    (pin "1")
    (instances
      (project "data-center-rdimm-ddr4-tester"
        (path ""
          (reference "#PWR031") (unit 1)
        )
      )
    )
  )

  (symbol (lib_id "antmicroCapacitors0603:C_10n_0603") (at 97.155 89.535 270) (unit 1)
    (in_bom yes) (on_board yes) (dnp no)
    (property "Reference" "C113" (at 97.79 90.17 90)
      (effects (font (size 1.524 1.524)) (justify left))
    )
    (property "Value" "C_10n_0603" (at 86.995 109.855 0)
      (effects (font (size 1.27 1.27) (thickness 0.15)) (justify left bottom) hide)
    )
    (property "Footprint" "antmicro-footprints:C_0603_1608Metric" (at 84.455 109.855 0)
      (effects (font (size 1.27 1.27) (thickness 0.15)) (justify left bottom) hide)
    )
    (property "Datasheet" " " (at 81.915 109.855 0)
      (effects (font (size 1.27 1.27) (thickness 0.15)) (justify left bottom) hide)
    )
    (property "Manufacturer" "AVX" (at 76.835 109.855 0)
      (effects (font (size 1.27 1.27) (thickness 0.15)) (justify left bottom) hide)
    )
    (property "MPN" "06031C103JAT2A" (at 79.375 109.855 0)
      (effects (font (size 1.27 1.27) (thickness 0.15)) (justify left bottom) hide)
    )
    (property "Val" "10n" (at 97.79 93.98 90)
      (effects (font (size 1.27 1.27) (thickness 0.15)) (justify left))
    )
    (property "License" "Apache-2.0" (at 74.295 109.855 0)
      (effects (font (size 1.27 1.27) (thickness 0.15)) (justify left bottom) hide)
    )
    (property "Author" "Antmicro" (at 71.755 109.855 0)
      (effects (font (size 1.27 1.27) (thickness 0.15)) (justify left bottom) hide)
    )
    (property "Voltage" "" (at 69.215 109.855 0)
      (effects (font (size 1.27 1.27)) (justify left bottom) hide)
    )
    (property "Dielectric" "" (at 66.675 109.855 0)
      (effects (font (size 1.27 1.27)) (justify left bottom) hide)
    )
    (pin "1")
    (pin "2")
    (instances
      (project "data-center-rdimm-ddr4-tester"
        (path ""
          (reference "C113") (unit 1)
        )
      )
    )
  )

  (symbol (lib_id "antmicropower:GND") (at 97.155 94.615 0) (unit 1)
    (in_bom yes) (on_board yes) (dnp no) (fields_autoplaced)
    (property "Reference" "#PWR032" (at 97.155 100.965 0)
      (effects (font (size 1.27 1.27)) hide)
    )
    (property "Value" "GND" (at 97.155 99.695 0)
      (effects (font (size 1.27 1.27)))
    )
    (property "Footprint" "" (at 97.155 94.615 0)
      (effects (font (size 1.27 1.27)) hide)
    )
    (property "Datasheet" "" (at 97.155 94.615 0)
      (effects (font (size 1.27 1.27)) hide)
    )
    (property "Author" "Antmicro" (at 106.045 102.235 0)
      (effects (font (size 1.27 1.27) (thickness 0.15)) (justify left bottom) hide)
    )
    (property "License" "Apache-2.0" (at 106.045 104.775 0)
      (effects (font (size 1.27 1.27) (thickness 0.15)) (justify left bottom) hide)
    )
    (pin "1")
    (instances
      (project "data-center-rdimm-ddr4-tester"
        (path ""
          (reference "#PWR032") (unit 1)
        )
      )
    )
  )

  (symbol (lib_id "antmicroTestPoints:TP_1mm_SMD") (at 279.4 99.06 0) (unit 1)
    (in_bom yes) (on_board yes) (dnp no) (fields_autoplaced)
    (property "Reference" "5V0" (at 284.48 99.0599 0)
      (effects (font (size 1.27 1.27)) (justify left))
    )
    (property "Value" "TP_1mm_SMD" (at 294.64 106.68 0)
      (effects (font (size 1.27 1.27) (thickness 0.15)) (justify left bottom) hide)
    )
    (property "Footprint" "antmicro-footprints:TP_SMD_1mm" (at 294.64 109.22 0)
      (effects (font (size 1.27 1.27) (thickness 0.15)) (justify left bottom) hide)
    )
    (property "Datasheet" "" (at 294.64 111.76 0)
      (effects (font (size 1.27 1.27) (thickness 0.15)) (justify left bottom) hide)
    )
    (property "MPN" "" (at 279.4 99.06 0)
      (effects (font (size 1.27 1.27)) hide)
    )
    (property "Manufacturer" "" (at 279.4 99.06 0)
      (effects (font (size 1.27 1.27)) hide)
    )
    (property "Author" "Antmicro" (at 294.64 114.3 0)
      (effects (font (size 1.27 1.27) (thickness 0.15)) (justify left bottom) hide)
    )
    (property "License" "Apache-2.0" (at 294.64 116.84 0)
      (effects (font (size 1.27 1.27) (thickness 0.15)) (justify left bottom) hide)
    )
    (pin "1")
    (instances
      (project "data-center-rdimm-ddr4-tester"
        (path ""
          (reference "5V0") (unit 1)
        )
      )
    )
  )

  (symbol (lib_id "antmicroTestPoints:TP_1mm_SMD") (at 300.355 92.71 0) (unit 1)
    (in_bom yes) (on_board yes) (dnp no) (fields_autoplaced)
    (property "Reference" "2V5" (at 306.07 92.7099 0)
      (effects (font (size 1.27 1.27)) (justify left))
    )
    (property "Value" "TP_1mm_SMD" (at 315.595 100.33 0)
      (effects (font (size 1.27 1.27) (thickness 0.15)) (justify left bottom) hide)
    )
    (property "Footprint" "antmicro-footprints:TP_SMD_1mm" (at 315.595 102.87 0)
      (effects (font (size 1.27 1.27) (thickness 0.15)) (justify left bottom) hide)
    )
    (property "Datasheet" "" (at 315.595 105.41 0)
      (effects (font (size 1.27 1.27) (thickness 0.15)) (justify left bottom) hide)
    )
    (property "MPN" "" (at 300.355 92.71 0)
      (effects (font (size 1.27 1.27)) hide)
    )
    (property "Manufacturer" "" (at 300.355 92.71 0)
      (effects (font (size 1.27 1.27)) hide)
    )
    (property "Author" "Antmicro" (at 315.595 107.95 0)
      (effects (font (size 1.27 1.27) (thickness 0.15)) (justify left bottom) hide)
    )
    (property "License" "Apache-2.0" (at 315.595 110.49 0)
      (effects (font (size 1.27 1.27) (thickness 0.15)) (justify left bottom) hide)
    )
    (pin "1")
    (instances
      (project "data-center-rdimm-ddr4-tester"
        (path ""
          (reference "2V5") (unit 1)
        )
      )
    )
  )

  (symbol (lib_id "antmicroTestPoints:TP_1mm_SMD") (at 300.355 95.25 0) (unit 1)
    (in_bom yes) (on_board yes) (dnp no) (fields_autoplaced)
    (property "Reference" "1V2" (at 306.07 95.2499 0)
      (effects (font (size 1.27 1.27)) (justify left))
    )
    (property "Value" "TP_1mm_SMD" (at 315.595 102.87 0)
      (effects (font (size 1.27 1.27) (thickness 0.15)) (justify left bottom) hide)
    )
    (property "Footprint" "antmicro-footprints:TP_SMD_1mm" (at 315.595 105.41 0)
      (effects (font (size 1.27 1.27) (thickness 0.15)) (justify left bottom) hide)
    )
    (property "Datasheet" "" (at 315.595 107.95 0)
      (effects (font (size 1.27 1.27) (thickness 0.15)) (justify left bottom) hide)
    )
    (property "MPN" "" (at 300.355 95.25 0)
      (effects (font (size 1.27 1.27)) hide)
    )
    (property "Manufacturer" "" (at 300.355 95.25 0)
      (effects (font (size 1.27 1.27)) hide)
    )
    (property "Author" "Antmicro" (at 315.595 110.49 0)
      (effects (font (size 1.27 1.27) (thickness 0.15)) (justify left bottom) hide)
    )
    (property "License" "Apache-2.0" (at 315.595 113.03 0)
      (effects (font (size 1.27 1.27) (thickness 0.15)) (justify left bottom) hide)
    )
    (pin "1")
    (instances
      (project "data-center-rdimm-ddr4-tester"
        (path ""
          (reference "1V2") (unit 1)
        )
      )
    )
  )

  (symbol (lib_id "antmicroTestPoints:TP_1mm_SMD") (at 300.355 97.79 0) (unit 1)
    (in_bom yes) (on_board yes) (dnp no) (fields_autoplaced)
    (property "Reference" "0V6" (at 306.07 97.7899 0)
      (effects (font (size 1.27 1.27)) (justify left))
    )
    (property "Value" "TP_1mm_SMD" (at 315.595 105.41 0)
      (effects (font (size 1.27 1.27) (thickness 0.15)) (justify left bottom) hide)
    )
    (property "Footprint" "antmicro-footprints:TP_SMD_1mm" (at 315.595 107.95 0)
      (effects (font (size 1.27 1.27) (thickness 0.15)) (justify left bottom) hide)
    )
    (property "Datasheet" "" (at 315.595 110.49 0)
      (effects (font (size 1.27 1.27) (thickness 0.15)) (justify left bottom) hide)
    )
    (property "MPN" "" (at 300.355 97.79 0)
      (effects (font (size 1.27 1.27)) hide)
    )
    (property "Manufacturer" "" (at 300.355 97.79 0)
      (effects (font (size 1.27 1.27)) hide)
    )
    (property "Author" "Antmicro" (at 315.595 113.03 0)
      (effects (font (size 1.27 1.27) (thickness 0.15)) (justify left bottom) hide)
    )
    (property "License" "Apache-2.0" (at 315.595 115.57 0)
      (effects (font (size 1.27 1.27) (thickness 0.15)) (justify left bottom) hide)
    )
    (pin "1")
    (instances
      (project "data-center-rdimm-ddr4-tester"
        (path ""
          (reference "0V6") (unit 1)
        )
      )
    )
  )

  (symbol (lib_id "antmicropower:GND") (at 66.04 153.67 0) (unit 1)
    (in_bom yes) (on_board yes) (dnp no) (fields_autoplaced)
    (property "Reference" "#PWR0186" (at 66.04 160.02 0)
      (effects (font (size 1.27 1.27)) hide)
    )
    (property "Value" "GND" (at 66.04 158.75 0)
      (effects (font (size 1.27 1.27)))
    )
    (property "Footprint" "" (at 66.04 153.67 0)
      (effects (font (size 1.27 1.27)) hide)
    )
    (property "Datasheet" "" (at 66.04 153.67 0)
      (effects (font (size 1.27 1.27)) hide)
    )
    (property "Author" "Antmicro" (at 74.93 161.29 0)
      (effects (font (size 1.27 1.27) (thickness 0.15)) (justify left bottom) hide)
    )
    (property "License" "Apache-2.0" (at 74.93 163.83 0)
      (effects (font (size 1.27 1.27) (thickness 0.15)) (justify left bottom) hide)
    )
    (pin "1")
    (instances
      (project "data-center-rdimm-ddr4-tester"
        (path ""
          (reference "#PWR0186") (unit 1)
        )
      )
    )
  )

  (symbol (lib_id "antmicropower:GND") (at 112.395 148.59 0) (unit 1)
    (in_bom yes) (on_board yes) (dnp no)
    (property "Reference" "#PWR0183" (at 112.395 154.94 0)
      (effects (font (size 1.27 1.27)) hide)
    )
    (property "Value" "GND" (at 112.395 152.4 0)
      (effects (font (size 1.27 1.27)))
    )
    (property "Footprint" "" (at 112.395 148.59 0)
      (effects (font (size 1.27 1.27)) hide)
    )
    (property "Datasheet" "" (at 112.395 148.59 0)
      (effects (font (size 1.27 1.27)) hide)
    )
    (property "Author" "Antmicro" (at 121.285 156.21 0)
      (effects (font (size 1.27 1.27) (thickness 0.15)) (justify left bottom) hide)
    )
    (property "License" "Apache-2.0" (at 121.285 158.75 0)
      (effects (font (size 1.27 1.27) (thickness 0.15)) (justify left bottom) hide)
    )
    (pin "1")
    (instances
      (project "data-center-rdimm-ddr4-tester"
        (path ""
          (reference "#PWR0183") (unit 1)
        )
      )
    )
  )

  (symbol (lib_id "antmicroCapacitorsmisc:C_47u_16V_1206") (at 22.86 116.205 270) (unit 1)
    (in_bom yes) (on_board yes) (dnp no)
    (property "Reference" "C116" (at 23.495 116.84 90)
      (effects (font (size 1.524 1.524)) (justify left))
    )
    (property "Value" "C_47u_16V_1206" (at 12.7 136.525 0)
      (effects (font (size 1.27 1.27) (thickness 0.15)) (justify left bottom) hide)
    )
    (property "Footprint" "antmicro-footprints:C_1206_3216Metric" (at 10.16 136.525 0)
      (effects (font (size 1.27 1.27) (thickness 0.15)) (justify left bottom) hide)
    )
    (property "Datasheet" " " (at 7.62 136.525 0)
      (effects (font (size 1.27 1.27) (thickness 0.15)) (justify left bottom) hide)
    )
    (property "Manufacturer" "TDK" (at 2.54 136.525 0)
      (effects (font (size 1.27 1.27) (thickness 0.15)) (justify left bottom) hide)
    )
    (property "MPN" "C3216X5R1C476M160AB" (at 5.08 136.525 0)
      (effects (font (size 1.27 1.27) (thickness 0.15)) (justify left bottom) hide)
    )
    (property "Val" "47u/16V" (at 23.495 120.65 90)
      (effects (font (size 1.27 1.27) (thickness 0.15)) (justify left))
    )
    (property "License" "Apache-2.0" (at 0 136.525 0)
      (effects (font (size 1.27 1.27) (thickness 0.15)) (justify left bottom) hide)
    )
    (property "Author" "Antmicro" (at -2.54 136.525 0)
      (effects (font (size 1.27 1.27) (thickness 0.15)) (justify left bottom) hide)
    )
    (property "Voltage" "" (at -5.08 136.525 0)
      (effects (font (size 1.27 1.27)) (justify left bottom) hide)
    )
    (property "Dielectric" "" (at -7.62 136.525 0)
      (effects (font (size 1.27 1.27)) (justify left bottom) hide)
    )
    (pin "1")
    (pin "2")
    (instances
      (project "data-center-rdimm-ddr4-tester"
        (path ""
          (reference "C116") (unit 1)
        )
      )
    )
  )

  (symbol (lib_id "data-center-rdimm-ddr4-tester:L_7u2_7.9A_WE-PDF") (at 115.57 139.7 0) (unit 1)
    (in_bom yes) (on_board yes) (dnp no)
    (property "Reference" "L6" (at 118.11 135.89 0)
      (effects (font (size 1.524 1.524)))
    )
    (property "Value" "L_7u2_7.9A_WE-PDF" (at 129.54 142.24 0)
      (effects (font (size 1.27 1.27) (thickness 0.15)) (justify left bottom) hide)
    )
    (property "Footprint" "data-center-rdimm-ddr4-tester-footprints:L_WE-PDF" (at 129.54 147.32 0)
      (effects (font (size 1.27 1.27) (thickness 0.15)) (justify left bottom) hide)
    )
    (property "Datasheet" "https://www.we-online.com/catalog/datasheet/7447798720.pdf" (at 129.54 149.86 0)
      (effects (font (size 1.27 1.27) (thickness 0.15)) (justify left bottom) hide)
    )
    (property "Manufacturer" "Würth Elektronik" (at 129.54 152.4 0)
      (effects (font (size 1.27 1.27) (thickness 0.15)) (justify left bottom) hide)
    )
    (property "MPN" "7447798720" (at 129.54 154.94 0)
      (effects (font (size 1.27 1.27) (thickness 0.15)) (justify left bottom) hide)
    )
    (property "Val" "7u2/7.9A" (at 118.11 137.795 0)
      (effects (font (size 1.27 1.27) (thickness 0.15)))
    )
    (property "ISat" "" (at 129.54 156.21 0)
      (effects (font (size 1.27 1.27)) (justify left) hide)
    )
    (property "IMax" "" (at 129.54 160.02 0)
      (effects (font (size 1.27 1.27) (thickness 0.15)) (justify left bottom) hide)
    )
    (property "Size" "10.2x10.2" (at 129.54 162.56 0)
      (effects (font (size 1.27 1.27) (thickness 0.15)) (justify left bottom) hide)
    )
    (property "Author" "Antmicro" (at 129.54 165.1 0)
      (effects (font (size 1.27 1.27) (thickness 0.15)) (justify left bottom) hide)
    )
    (property "License" "Apache-2.0" (at 129.54 167.64 0)
      (effects (font (size 1.27 1.27) (thickness 0.15)) (justify left bottom) hide)
    )
    (pin "1")
    (pin "2")
    (instances
      (project "data-center-rdimm-ddr4-tester"
        (path ""
          (reference "L6") (unit 1)
        )
      )
    )
  )

  (symbol (lib_id "antmicroCapacitorsmisc:C_47u_16V_1206") (at 34.29 116.205 270) (unit 1)
    (in_bom yes) (on_board yes) (dnp no)
    (property "Reference" "C117" (at 34.925 116.84 90)
      (effects (font (size 1.524 1.524)) (justify left))
    )
    (property "Value" "C_47u_16V_1206" (at 24.13 136.525 0)
      (effects (font (size 1.27 1.27) (thickness 0.15)) (justify left bottom) hide)
    )
    (property "Footprint" "antmicro-footprints:C_1206_3216Metric" (at 21.59 136.525 0)
      (effects (font (size 1.27 1.27) (thickness 0.15)) (justify left bottom) hide)
    )
    (property "Datasheet" " " (at 19.05 136.525 0)
      (effects (font (size 1.27 1.27) (thickness 0.15)) (justify left bottom) hide)
    )
    (property "Manufacturer" "TDK" (at 13.97 136.525 0)
      (effects (font (size 1.27 1.27) (thickness 0.15)) (justify left bottom) hide)
    )
    (property "MPN" "C3216X5R1C476M160AB" (at 16.51 136.525 0)
      (effects (font (size 1.27 1.27) (thickness 0.15)) (justify left bottom) hide)
    )
    (property "Val" "47u/16V" (at 34.925 120.65 90)
      (effects (font (size 1.27 1.27) (thickness 0.15)) (justify left))
    )
    (property "License" "Apache-2.0" (at 11.43 136.525 0)
      (effects (font (size 1.27 1.27) (thickness 0.15)) (justify left bottom) hide)
    )
    (property "Author" "Antmicro" (at 8.89 136.525 0)
      (effects (font (size 1.27 1.27) (thickness 0.15)) (justify left bottom) hide)
    )
    (property "Voltage" "" (at 6.35 136.525 0)
      (effects (font (size 1.27 1.27)) (justify left bottom) hide)
    )
    (property "Dielectric" "" (at 3.81 136.525 0)
      (effects (font (size 1.27 1.27)) (justify left bottom) hide)
    )
    (pin "1")
    (pin "2")
    (instances
      (project "data-center-rdimm-ddr4-tester"
        (path ""
          (reference "C117") (unit 1)
        )
      )
    )
  )

  (symbol (lib_id "antmicroCapacitorsmisc:C_47u_16V_1206") (at 45.72 116.205 270) (unit 1)
    (in_bom yes) (on_board yes) (dnp no)
    (property "Reference" "C118" (at 46.355 116.84 90)
      (effects (font (size 1.524 1.524)) (justify left))
    )
    (property "Value" "C_47u_16V_1206" (at 35.56 136.525 0)
      (effects (font (size 1.27 1.27) (thickness 0.15)) (justify left bottom) hide)
    )
    (property "Footprint" "antmicro-footprints:C_1206_3216Metric" (at 33.02 136.525 0)
      (effects (font (size 1.27 1.27) (thickness 0.15)) (justify left bottom) hide)
    )
    (property "Datasheet" " " (at 30.48 136.525 0)
      (effects (font (size 1.27 1.27) (thickness 0.15)) (justify left bottom) hide)
    )
    (property "Manufacturer" "TDK" (at 25.4 136.525 0)
      (effects (font (size 1.27 1.27) (thickness 0.15)) (justify left bottom) hide)
    )
    (property "MPN" "C3216X5R1C476M160AB" (at 27.94 136.525 0)
      (effects (font (size 1.27 1.27) (thickness 0.15)) (justify left bottom) hide)
    )
    (property "Val" "47u/16V" (at 46.355 120.65 90)
      (effects (font (size 1.27 1.27) (thickness 0.15)) (justify left))
    )
    (property "License" "Apache-2.0" (at 22.86 136.525 0)
      (effects (font (size 1.27 1.27) (thickness 0.15)) (justify left bottom) hide)
    )
    (property "Author" "Antmicro" (at 20.32 136.525 0)
      (effects (font (size 1.27 1.27) (thickness 0.15)) (justify left bottom) hide)
    )
    (property "Voltage" "" (at 17.78 136.525 0)
      (effects (font (size 1.27 1.27)) (justify left bottom) hide)
    )
    (property "Dielectric" "" (at 15.24 136.525 0)
      (effects (font (size 1.27 1.27)) (justify left bottom) hide)
    )
    (pin "1")
    (pin "2")
    (instances
      (project "data-center-rdimm-ddr4-tester"
        (path ""
          (reference "C118") (unit 1)
        )
      )
    )
  )

  (symbol (lib_id "antmicroDiodesRectifiersSingle:PDS760") (at 112.395 148.59 90) (unit 1)
    (in_bom yes) (on_board yes) (dnp no) (fields_autoplaced)
    (property "Reference" "D2" (at 115.57 143.256 90)
      (effects (font (size 1.524 1.524)) (justify right))
    )
    (property "Value" "PDS760" (at 115.57 146.4309 90)
      (effects (font (size 1.27 1.27) (thickness 0.15)) (justify right))
    )
    (property "Footprint" "antmicro-footprints:PowerDI5" (at 122.555 125.73 0)
      (effects (font (size 1.27 1.27) (thickness 0.15)) (justify left bottom) hide)
    )
    (property "Datasheet" "https://www.diodes.com/assets/Datasheets/ds30470.pdf" (at 125.095 125.73 0)
      (effects (font (size 1.27 1.27) (thickness 0.15)) (justify left bottom) hide)
    )
    (property "Manufacturer" "Diodes Incorporated" (at 127.635 125.73 0)
      (effects (font (size 1.27 1.27) (thickness 0.15)) (justify left bottom) hide)
    )
    (property "MPN" "PDS760-13" (at 130.175 125.73 0)
      (effects (font (size 1.27 1.27) (thickness 0.15)) (justify left bottom) hide)
    )
    (property "Author" "Antmicro" (at 132.715 125.73 0)
      (effects (font (size 1.27 1.27) (thickness 0.15)) (justify left bottom) hide)
    )
    (property "License" "Apache-2.0" (at 135.255 125.73 0)
      (effects (font (size 1.27 1.27) (thickness 0.15)) (justify left bottom) hide)
    )
    (pin "A")
    (pin "C")
    (instances
      (project "data-center-rdimm-ddr4-tester"
        (path ""
          (reference "D2") (unit 1)
        )
      )
    )
  )

  (symbol (lib_id "antmicroFixedInductors:L_4u7_2.8A_2020") (at 73.66 26.67 0) (unit 1)
    (in_bom yes) (on_board yes) (dnp no)
    (property "Reference" "L1" (at 76.2 22.225 0)
      (effects (font (size 1.524 1.524)))
    )
    (property "Value" "L_4u7_2.8A_2020" (at 87.63 29.21 0)
      (effects (font (size 1.27 1.27) (thickness 0.15)) (justify left bottom) hide)
    )
    (property "Footprint" "antmicro-footprints:L_2020_5252Metric" (at 87.63 34.29 0)
      (effects (font (size 1.27 1.27) (thickness 0.15)) (justify left bottom) hide)
    )
    (property "Datasheet" "" (at 87.63 36.83 0)
      (effects (font (size 1.27 1.27) (thickness 0.15)) (justify left bottom) hide)
    )
    (property "Manufacturer" "Vishay" (at 87.63 39.37 0)
      (effects (font (size 1.27 1.27) (thickness 0.15)) (justify left bottom) hide)
    )
    (property "MPN" "IHLP2020BZER4R7M01" (at 87.63 41.91 0)
      (effects (font (size 1.27 1.27) (thickness 0.15)) (justify left bottom) hide)
    )
    (property "Val" "4u7/2.8A" (at 76.2 24.765 0)
      (effects (font (size 1.27 1.27) (thickness 0.15)))
    )
    (property "ISat" "" (at 87.63 43.18 0)
      (effects (font (size 1.27 1.27)) (justify left) hide)
    )
    (property "IMax" "" (at 87.63 46.99 0)
      (effects (font (size 1.27 1.27) (thickness 0.15)) (justify left bottom) hide)
    )
    (property "Size" "5.18x5.18" (at 87.63 49.53 0)
      (effects (font (size 1.27 1.27) (thickness 0.15)) (justify left bottom) hide)
    )
    (property "Author" "Antmicro" (at 87.63 52.07 0)
      (effects (font (size 1.27 1.27) (thickness 0.15)) (justify left bottom) hide)
    )
    (property "License" "Apache-2.0" (at 87.63 54.61 0)
      (effects (font (size 1.27 1.27) (thickness 0.15)) (justify left bottom) hide)
    )
    (pin "1")
    (pin "2")
    (instances
      (project "data-center-rdimm-ddr4-tester"
        (path ""
          (reference "L1") (unit 1)
        )
      )
    )
  )

  (symbol (lib_id "data-center-rdimm-ddr4-tester:L_680n_6.1A_1210") (at 90.17 41.91 0) (unit 1)
    (in_bom yes) (on_board yes) (dnp no)
    (property "Reference" "L2" (at 92.71 38.1 0)
      (effects (font (size 1.524 1.524)))
    )
    (property "Value" "L_680n_6.1A_1210" (at 104.14 44.45 0)
      (effects (font (size 1.27 1.27) (thickness 0.15)) (justify left bottom) hide)
    )
    (property "Footprint" "data-center-rdimm-ddr4-tester-footprints:L_1210_3225Metric" (at 104.14 49.53 0)
      (effects (font (size 1.27 1.27) (thickness 0.15)) (justify left bottom) hide)
    )
    (property "Datasheet" "https://www.murata.com/en-global/products/productdetail?partno=DFE322512F-R68M%23" (at 104.14 52.07 0)
      (effects (font (size 1.27 1.27) (thickness 0.15)) (justify left bottom) hide)
    )
    (property "Manufacturer" "Murata" (at 104.14 54.61 0)
      (effects (font (size 1.27 1.27) (thickness 0.15)) (justify left bottom) hide)
    )
    (property "MPN" "DFE322512F-R68M=P2" (at 104.14 57.15 0)
      (effects (font (size 1.27 1.27) (thickness 0.15)) (justify left bottom) hide)
    )
    (property "Val" "680n/6.1A" (at 92.71 40.005 0)
      (effects (font (size 1.27 1.27) (thickness 0.15)))
    )
    (property "ISat" "" (at 104.14 58.42 0)
      (effects (font (size 1.27 1.27)) (justify left) hide)
    )
    (property "IMax" "" (at 104.14 62.23 0)
      (effects (font (size 1.27 1.27) (thickness 0.15)) (justify left bottom) hide)
    )
    (property "Size" "3.2x2.5" (at 104.14 64.77 0)
      (effects (font (size 1.27 1.27) (thickness 0.15)) (justify left bottom) hide)
    )
    (property "Author" "Antmicro" (at 104.14 67.31 0)
      (effects (font (size 1.27 1.27) (thickness 0.15)) (justify left bottom) hide)
    )
    (property "License" "Apache-2.0" (at 104.14 69.85 0)
      (effects (font (size 1.27 1.27) (thickness 0.15)) (justify left bottom) hide)
    )
    (pin "1")
    (pin "2")
    (instances
      (project "data-center-rdimm-ddr4-tester"
        (path ""
          (reference "L2") (unit 1)
        )
      )
    )
  )

  (symbol (lib_id "antmicroCapacitors0603:C_47u_0603") (at 137.795 140.97 270) (unit 1)
    (in_bom yes) (on_board yes) (dnp no)
    (property "Reference" "C180" (at 138.43 141.605 90)
      (effects (font (size 1.524 1.524)) (justify left))
    )
    (property "Value" "C_47u_0603" (at 127.635 161.29 0)
      (effects (font (size 1.27 1.27) (thickness 0.15)) (justify left bottom) hide)
    )
    (property "Footprint" "antmicro-footprints:C_0603_1608Metric" (at 125.095 161.29 0)
      (effects (font (size 1.27 1.27) (thickness 0.15)) (justify left bottom) hide)
    )
    (property "Datasheet" " " (at 122.555 161.29 0)
      (effects (font (size 1.27 1.27) (thickness 0.15)) (justify left bottom) hide)
    )
    (property "Manufacturer" "Murata" (at 117.475 161.29 0)
      (effects (font (size 1.27 1.27) (thickness 0.15)) (justify left bottom) hide)
    )
    (property "MPN" "GRM188R60J476ME15D" (at 120.015 161.29 0)
      (effects (font (size 1.27 1.27) (thickness 0.15)) (justify left bottom) hide)
    )
    (property "Val" "47u" (at 138.43 145.415 90)
      (effects (font (size 1.27 1.27) (thickness 0.15)) (justify left))
    )
    (property "License" "Apache-2.0" (at 114.935 161.29 0)
      (effects (font (size 1.27 1.27) (thickness 0.15)) (justify left bottom) hide)
    )
    (property "Author" "Antmicro" (at 112.395 161.29 0)
      (effects (font (size 1.27 1.27) (thickness 0.15)) (justify left bottom) hide)
    )
    (property "Voltage" "" (at 109.855 161.29 0)
      (effects (font (size 1.27 1.27)) (justify left bottom) hide)
    )
    (property "Dielectric" "" (at 107.315 161.29 0)
      (effects (font (size 1.27 1.27)) (justify left bottom) hide)
    )
    (pin "1")
    (pin "2")
    (instances
      (project "data-center-rdimm-ddr4-tester"
        (path ""
          (reference "C180") (unit 1)
        )
      )
    )
  )

  (symbol (lib_id "antmicroCapacitors0603:C_47u_0603") (at 153.035 140.97 270) (unit 1)
    (in_bom yes) (on_board yes) (dnp no)
    (property "Reference" "C183" (at 153.67 141.605 90)
      (effects (font (size 1.524 1.524)) (justify left))
    )
    (property "Value" "C_47u_0603" (at 142.875 161.29 0)
      (effects (font (size 1.27 1.27) (thickness 0.15)) (justify left bottom) hide)
    )
    (property "Footprint" "antmicro-footprints:C_0603_1608Metric" (at 140.335 161.29 0)
      (effects (font (size 1.27 1.27) (thickness 0.15)) (justify left bottom) hide)
    )
    (property "Datasheet" " " (at 137.795 161.29 0)
      (effects (font (size 1.27 1.27) (thickness 0.15)) (justify left bottom) hide)
    )
    (property "Manufacturer" "Murata" (at 132.715 161.29 0)
      (effects (font (size 1.27 1.27) (thickness 0.15)) (justify left bottom) hide)
    )
    (property "MPN" "GRM188R60J476ME15D" (at 135.255 161.29 0)
      (effects (font (size 1.27 1.27) (thickness 0.15)) (justify left bottom) hide)
    )
    (property "Val" "47u" (at 154.305 145.415 90)
      (effects (font (size 1.27 1.27) (thickness 0.15)) (justify left))
    )
    (property "License" "Apache-2.0" (at 130.175 161.29 0)
      (effects (font (size 1.27 1.27) (thickness 0.15)) (justify left bottom) hide)
    )
    (property "Author" "Antmicro" (at 127.635 161.29 0)
      (effects (font (size 1.27 1.27) (thickness 0.15)) (justify left bottom) hide)
    )
    (property "Voltage" "" (at 125.095 161.29 0)
      (effects (font (size 1.27 1.27)) (justify left bottom) hide)
    )
    (property "Dielectric" "" (at 122.555 161.29 0)
      (effects (font (size 1.27 1.27)) (justify left bottom) hide)
    )
    (pin "1")
    (pin "2")
    (instances
      (project "data-center-rdimm-ddr4-tester"
        (path ""
          (reference "C183") (unit 1)
        )
      )
    )
  )

  (symbol (lib_id "antmicropower:GND") (at 125.095 162.56 0) (unit 1)
    (in_bom yes) (on_board yes) (dnp no) (fields_autoplaced)
    (property "Reference" "#PWR0185" (at 125.095 168.91 0)
      (effects (font (size 1.27 1.27)) hide)
    )
    (property "Value" "GND" (at 125.095 167.64 0)
      (effects (font (size 1.27 1.27)))
    )
    (property "Footprint" "" (at 125.095 162.56 0)
      (effects (font (size 1.27 1.27)) hide)
    )
    (property "Datasheet" "" (at 125.095 162.56 0)
      (effects (font (size 1.27 1.27)) hide)
    )
    (property "Author" "Antmicro" (at 133.985 170.18 0)
      (effects (font (size 1.27 1.27) (thickness 0.15)) (justify left bottom) hide)
    )
    (property "License" "Apache-2.0" (at 133.985 172.72 0)
      (effects (font (size 1.27 1.27) (thickness 0.15)) (justify left bottom) hide)
    )
    (pin "1")
    (instances
      (project "data-center-rdimm-ddr4-tester"
        (path ""
          (reference "#PWR0185") (unit 1)
        )
      )
    )
  )

  (symbol (lib_id "antmicroResistors0402:R_100k_0402") (at 103.505 123.19 270) (unit 1)
    (in_bom yes) (on_board yes) (dnp no) (fields_autoplaced)
    (property "Reference" "R122" (at 105.41 124.46 90)
      (effects (font (size 1.524 1.524)) (justify left))
    )
    (property "Value" "R_100k_0402" (at 90.805 143.51 0)
      (effects (font (size 1.27 1.27) (thickness 0.15)) (justify left bottom) hide)
    )
    (property "Footprint" "antmicro-footprints:R_0402_1005Metric" (at 88.265 143.51 0)
      (effects (font (size 1.27 1.27) (thickness 0.15)) (justify left bottom) hide)
    )
    (property "Datasheet" "https://www.bourns.com/docs/product-datasheets/cr.pdf" (at 85.725 143.51 0)
      (effects (font (size 1.27 1.27) (thickness 0.15)) (justify left bottom) hide)
    )
    (property "Manufacturer" "Bourns" (at 80.645 143.51 0)
      (effects (font (size 1.27 1.27) (thickness 0.15)) (justify left bottom) hide)
    )
    (property "MPN" "CR0402-FX-1003GLF" (at 83.185 143.51 0)
      (effects (font (size 1.27 1.27) (thickness 0.15)) (justify left bottom) hide)
    )
    (property "Val" "100k" (at 105.41 127.6349 90)
      (effects (font (size 1.27 1.27) (thickness 0.15)) (justify left))
    )
    (property "License" "Apache-2.0" (at 78.105 143.51 0)
      (effects (font (size 1.27 1.27) (thickness 0.15)) (justify left bottom) hide)
    )
    (property "Author" "Antmicro" (at 75.565 143.51 0)
      (effects (font (size 1.27 1.27) (thickness 0.15)) (justify left bottom) hide)
    )
    (property "Tolerance" "1%" (at 93.345 143.51 0)
      (effects (font (size 1.27 1.27)) (justify left bottom) hide)
    )
    (pin "1")
    (pin "2")
    (instances
      (project "data-center-rdimm-ddr4-tester"
        (path ""
          (reference "R122") (unit 1)
        )
      )
    )
  )

  (symbol (lib_id "antmicroCapacitors0402:C_47p_0402") (at 95.25 157.48 90) (mirror x) (unit 1)
    (in_bom yes) (on_board yes) (dnp no)
    (property "Reference" "C175" (at 92.71 159.3788 90)
      (effects (font (size 1.524 1.524)) (justify left))
    )
    (property "Value" "C_47p_0402" (at 105.41 177.8 0)
      (effects (font (size 1.27 1.27) (thickness 0.15)) (justify left bottom) hide)
    )
    (property "Footprint" "antmicro-footprints:C_0402_1005Metric" (at 107.95 177.8 0)
      (effects (font (size 1.27 1.27) (thickness 0.15)) (justify left bottom) hide)
    )
    (property "Datasheet" " " (at 110.49 177.8 0)
      (effects (font (size 1.27 1.27) (thickness 0.15)) (justify left bottom) hide)
    )
    (property "Manufacturer" "Murata" (at 115.57 177.8 0)
      (effects (font (size 1.27 1.27) (thickness 0.15)) (justify left bottom) hide)
    )
    (property "MPN" "GRM1555C1E470JA01D" (at 113.03 177.8 0)
      (effects (font (size 1.27 1.27) (thickness 0.15)) (justify left bottom) hide)
    )
    (property "Val" "47p" (at 92.71 161.925 90)
      (effects (font (size 1.27 1.27) (thickness 0.15)) (justify left))
    )
    (property "License" "Apache-2.0" (at 118.11 177.8 0)
      (effects (font (size 1.27 1.27) (thickness 0.15)) (justify left bottom) hide)
    )
    (property "Author" "Antmicro" (at 120.65 177.8 0)
      (effects (font (size 1.27 1.27) (thickness 0.15)) (justify left bottom) hide)
    )
    (property "Voltage" "" (at 123.19 177.8 0)
      (effects (font (size 1.27 1.27)) (justify left bottom) hide)
    )
    (property "Dielectric" "C0G" (at 125.73 177.8 0)
      (effects (font (size 1.27 1.27)) (justify left bottom) hide)
    )
    (pin "1")
    (pin "2")
    (instances
      (project "data-center-rdimm-ddr4-tester"
        (path ""
          (reference "C175") (unit 1)
        )
      )
    )
  )

  (symbol (lib_id "antmicroCapacitors0402:C_4n7_0402") (at 99.695 157.48 90) (mirror x) (unit 1)
    (in_bom yes) (on_board yes) (dnp no)
    (property "Reference" "C172" (at 102.235 159.385 90)
      (effects (font (size 1.524 1.524)) (justify right))
    )
    (property "Value" "C_4n7_0402" (at 109.855 177.8 0)
      (effects (font (size 1.27 1.27) (thickness 0.15)) (justify left bottom) hide)
    )
    (property "Footprint" "antmicro-footprints:C_0402_1005Metric" (at 112.395 177.8 0)
      (effects (font (size 1.27 1.27) (thickness 0.15)) (justify left bottom) hide)
    )
    (property "Datasheet" " " (at 114.935 177.8 0)
      (effects (font (size 1.27 1.27) (thickness 0.15)) (justify left bottom) hide)
    )
    (property "Manufacturer" "TDK" (at 120.015 177.8 0)
      (effects (font (size 1.27 1.27) (thickness 0.15)) (justify left bottom) hide)
    )
    (property "MPN" "CGA2B3X7S2A472K050BB" (at 117.475 177.8 0)
      (effects (font (size 1.27 1.27) (thickness 0.15)) (justify left bottom) hide)
    )
    (property "Val" "4n7" (at 102.235 161.9312 90)
      (effects (font (size 1.27 1.27) (thickness 0.15)) (justify right))
    )
    (property "License" "Apache-2.0" (at 122.555 177.8 0)
      (effects (font (size 1.27 1.27) (thickness 0.15)) (justify left bottom) hide)
    )
    (property "Author" "Antmicro" (at 125.095 177.8 0)
      (effects (font (size 1.27 1.27) (thickness 0.15)) (justify left bottom) hide)
    )
    (property "Voltage" "" (at 127.635 177.8 0)
      (effects (font (size 1.27 1.27)) (justify left bottom) hide)
    )
    (property "Dielectric" "" (at 130.175 177.8 0)
      (effects (font (size 1.27 1.27)) (justify left bottom) hide)
    )
    (pin "1")
    (pin "2")
    (instances
      (project "data-center-rdimm-ddr4-tester"
        (path ""
          (reference "C172") (unit 1)
        )
      )
    )
  )

  (symbol (lib_id "antmicroResistors0402:R_16k9_0402") (at 99.695 152.4 90) (mirror x) (unit 1)
    (in_bom yes) (on_board yes) (dnp no)
    (property "Reference" "R115" (at 101.6 153.6701 90)
      (effects (font (size 1.524 1.524)) (justify right))
    )
    (property "Value" "R_16k9_0402" (at 112.395 172.72 0)
      (effects (font (size 1.27 1.27) (thickness 0.15)) (justify left bottom) hide)
    )
    (property "Footprint" "antmicro-footprints:R_0402_1005Metric" (at 114.935 172.72 0)
      (effects (font (size 1.27 1.27) (thickness 0.15)) (justify left bottom) hide)
    )
    (property "Datasheet" "https://www.bourns.com/docs/product-datasheets/cr.pdf" (at 117.475 172.72 0)
      (effects (font (size 1.27 1.27) (thickness 0.15)) (justify left bottom) hide)
    )
    (property "Manufacturer" "Bourns" (at 122.555 172.72 0)
      (effects (font (size 1.27 1.27) (thickness 0.15)) (justify left bottom) hide)
    )
    (property "MPN" "CR0402-FX-1692GLF" (at 120.015 172.72 0)
      (effects (font (size 1.27 1.27) (thickness 0.15)) (justify left bottom) hide)
    )
    (property "Val" "16k9" (at 101.6 156.21 90)
      (effects (font (size 1.27 1.27) (thickness 0.15)) (justify right))
    )
    (property "License" "Apache-2.0" (at 125.095 172.72 0)
      (effects (font (size 1.27 1.27) (thickness 0.15)) (justify left bottom) hide)
    )
    (property "Author" "Antmicro" (at 127.635 172.72 0)
      (effects (font (size 1.27 1.27) (thickness 0.15)) (justify left bottom) hide)
    )
    (property "Tolerance" "1%" (at 109.855 172.72 0)
      (effects (font (size 1.27 1.27)) (justify left bottom) hide)
    )
    (pin "1")
    (pin "2")
    (instances
      (project "data-center-rdimm-ddr4-tester"
        (path ""
          (reference "R115") (unit 1)
        )
      )
    )
  )

  (symbol (lib_id "antmicropower:GND") (at 99.695 162.56 0) (mirror y) (unit 1)
    (in_bom yes) (on_board yes) (dnp no) (fields_autoplaced)
    (property "Reference" "#PWR0187" (at 99.695 168.91 0)
      (effects (font (size 1.27 1.27)) hide)
    )
    (property "Value" "GND" (at 99.695 167.64 0)
      (effects (font (size 1.27 1.27)))
    )
    (property "Footprint" "" (at 99.695 162.56 0)
      (effects (font (size 1.27 1.27)) hide)
    )
    (property "Datasheet" "" (at 99.695 162.56 0)
      (effects (font (size 1.27 1.27)) hide)
    )
    (property "Author" "Antmicro" (at 90.805 170.18 0)
      (effects (font (size 1.27 1.27) (thickness 0.15)) (justify left bottom) hide)
    )
    (property "License" "Apache-2.0" (at 90.805 172.72 0)
      (effects (font (size 1.27 1.27) (thickness 0.15)) (justify left bottom) hide)
    )
    (pin "1")
    (instances
      (project "data-center-rdimm-ddr4-tester"
        (path ""
          (reference "#PWR0187") (unit 1)
        )
      )
    )
  )

  (symbol (lib_id "antmicropower:GND") (at 95.25 162.56 0) (mirror y) (unit 1)
    (in_bom yes) (on_board yes) (dnp no) (fields_autoplaced)
    (property "Reference" "#PWR0188" (at 95.25 168.91 0)
      (effects (font (size 1.27 1.27)) hide)
    )
    (property "Value" "GND" (at 95.25 167.64 0)
      (effects (font (size 1.27 1.27)))
    )
    (property "Footprint" "" (at 95.25 162.56 0)
      (effects (font (size 1.27 1.27)) hide)
    )
    (property "Datasheet" "" (at 95.25 162.56 0)
      (effects (font (size 1.27 1.27)) hide)
    )
    (property "Author" "Antmicro" (at 86.36 170.18 0)
      (effects (font (size 1.27 1.27) (thickness 0.15)) (justify left bottom) hide)
    )
    (property "License" "Apache-2.0" (at 86.36 172.72 0)
      (effects (font (size 1.27 1.27) (thickness 0.15)) (justify left bottom) hide)
    )
    (pin "1")
    (instances
      (project "data-center-rdimm-ddr4-tester"
        (path ""
          (reference "#PWR0188") (unit 1)
        )
      )
    )
  )

  (symbol (lib_id "antmicropower:GND") (at 22.86 121.285 0) (unit 1)
    (in_bom yes) (on_board yes) (dnp no) (fields_autoplaced)
    (property "Reference" "#PWR0189" (at 22.86 127.635 0)
      (effects (font (size 1.27 1.27)) hide)
    )
    (property "Value" "GND" (at 22.86 126.365 0)
      (effects (font (size 1.27 1.27)))
    )
    (property "Footprint" "" (at 22.86 121.285 0)
      (effects (font (size 1.27 1.27)) hide)
    )
    (property "Datasheet" "" (at 22.86 121.285 0)
      (effects (font (size 1.27 1.27)) hide)
    )
    (property "Author" "Antmicro" (at 31.75 128.905 0)
      (effects (font (size 1.27 1.27) (thickness 0.15)) (justify left bottom) hide)
    )
    (property "License" "Apache-2.0" (at 31.75 131.445 0)
      (effects (font (size 1.27 1.27) (thickness 0.15)) (justify left bottom) hide)
    )
    (pin "1")
    (instances
      (project "data-center-rdimm-ddr4-tester"
        (path ""
          (reference "#PWR0189") (unit 1)
        )
      )
    )
  )

  (symbol (lib_id "antmicroBarrelAudioConnectors:BarrelJack_3167288") (at 316.23 236.855 0) (mirror y) (unit 1)
    (in_bom yes) (on_board yes) (dnp no)
    (property "Reference" "J3" (at 308.61 231.14 0)
      (effects (font (size 1.524 1.524)))
    )
    (property "Value" "BarrelJack_3167288" (at 302.26 241.2999 0)
      (effects (font (size 1.27 1.27) (thickness 0.15)) (justify left) hide)
    )
    (property "Footprint" "antmicro-footprints:BarrelJack_3167288_Horizontal" (at 298.45 247.015 0)
      (effects (font (size 1.27 1.27) (thickness 0.15)) (justify left bottom) hide)
    )
    (property "Datasheet" "https://www.farnell.com/datasheets/3167288.pdf" (at 298.45 249.555 0)
      (effects (font (size 1.27 1.27) (thickness 0.15)) (justify left bottom) hide)
    )
    (property "Manufacturer" "Multicomp Pro" (at 298.45 252.095 0)
      (effects (font (size 1.27 1.27) (thickness 0.15)) (justify left bottom) hide)
    )
    (property "MPN" "MJ-179PH" (at 308.61 233.68 0)
      (effects (font (size 1.27 1.27) (thickness 0.15)))
    )
    (property "Author" "Antmicro" (at 298.45 257.175 0)
      (effects (font (size 1.27 1.27) (thickness 0.15)) (justify left bottom) hide)
    )
    (property "License" "Apache-2.0" (at 298.45 259.715 0)
      (effects (font (size 1.27 1.27) (thickness 0.15)) (justify left bottom) hide)
    )
    (pin "1")
    (pin "2")
    (pin "3")
    (instances
      (project "data-center-rdimm-ddr4-tester"
        (path ""
          (reference "J3") (unit 1)
        )
      )
    )
  )

  (symbol (lib_id "antmicroResistors0402:R_5R1_0402") (at 70.485 36.83 0) (unit 1)
    (in_bom yes) (on_board yes) (dnp no)
    (property "Reference" "R35" (at 68.58 35.56 0)
      (effects (font (size 1.524 1.524)))
    )
    (property "Value" "R_5R1_0402" (at 90.805 49.53 0)
      (effects (font (size 1.27 1.27) (thickness 0.15)) (justify left bottom) hide)
    )
    (property "Footprint" "antmicro-footprints:R_0402_1005Metric" (at 90.805 52.07 0)
      (effects (font (size 1.27 1.27) (thickness 0.15)) (justify left bottom) hide)
    )
    (property "Datasheet" "https://www.bourns.com/docs/product-datasheets/cr.pdf" (at 90.805 54.61 0)
      (effects (font (size 1.27 1.27) (thickness 0.15)) (justify left bottom) hide)
    )
    (property "Manufacturer" "Bourns" (at 90.805 59.69 0)
      (effects (font (size 1.27 1.27) (thickness 0.15)) (justify left bottom) hide)
    )
    (property "MPN" "CR0402-FX-5R10GLF" (at 90.805 57.15 0)
      (effects (font (size 1.27 1.27) (thickness 0.15)) (justify left bottom) hide)
    )
    (property "Val" "5R1" (at 68.58 38.1 0)
      (effects (font (size 1.27 1.27) (thickness 0.15)))
    )
    (property "License" "Apache-2.0" (at 90.805 62.23 0)
      (effects (font (size 1.27 1.27) (thickness 0.15)) (justify left bottom) hide)
    )
    (property "Author" "Antmicro" (at 90.805 64.77 0)
      (effects (font (size 1.27 1.27) (thickness 0.15)) (justify left bottom) hide)
    )
    (property "Tolerance" "1%" (at 90.805 46.99 0)
      (effects (font (size 1.27 1.27)) (justify left bottom) hide)
    )
    (pin "1")
    (pin "2")
    (instances
      (project "data-center-rdimm-ddr4-tester"
        (path ""
          (reference "R35") (unit 1)
        )
      )
    )
  )

  (symbol (lib_id "antmicroPMICVoltageRegulatorsDCDCSwitchingControllers:TPS65295RJE") (at 41.91 26.67 0) (unit 1)
    (in_bom yes) (on_board yes) (dnp no)
    (property "Reference" "U2" (at 53.975 20.955 0)
      (effects (font (size 1.524 1.524)))
    )
    (property "Value" "TPS65295RJE" (at 53.975 21.59 0)
      (effects (font (size 1.27 1.27) (thickness 0.15)) hide)
    )
    (property "Footprint" "antmicro-footprints:TPS65295RJET" (at 83.82 35.56 0)
      (effects (font (size 1.27 1.27) (thickness 0.15)) (justify left bottom) hide)
    )
    (property "Datasheet" "https://www.ti.com/lit/ds/symlink/tps65295.pdf?ts=1678974348145&ref_url=https%253A%252F%252Fwww.ti.com%252Fproduct%252FTPS65295%252Fpart-details%252FTPS65295RJET%253Futm_source%253Dgoogle%2526utm_medium%253Dcpc%2526utm_campaign%253Docb-tistore-promo-app_opn_en-cpc-storeic-google-wwe%2526utm_content%253DDevice%2526ds_k%253DTPS65295RJET%2526DCM%253Dyes%2526gclid%253DCjwKCAjw_MqgBhAGEiwAnYOAenqZlHFYNIv8bo8LzLCLfbwSVYe5HxpiyTTTkdL5wSHfzakFHjgpQRoCDzsQAvD_BwE%2526gclsrc%253Daw.ds" (at 83.82 38.1 0)
      (effects (font (size 1.27 1.27) (thickness 0.15)) (justify left bottom) hide)
    )
    (property "MPN" "TPS65295RJET" (at 53.975 22.86 0)
      (effects (font (size 1.27 1.27) (thickness 0.15)))
    )
    (property "Manufacturer" "Texas Instruments" (at 83.82 43.18 0)
      (effects (font (size 1.27 1.27) (thickness 0.15)) (justify left bottom) hide)
    )
    (property "Author" "Antmicro" (at 83.82 45.72 0)
      (effects (font (size 1.27 1.27) (thickness 0.15)) (justify left bottom) hide)
    )
    (property "License" "Apache-2.0" (at 83.82 48.26 0)
      (effects (font (size 1.27 1.27) (thickness 0.15)) (justify left bottom) hide)
    )
    (pin "1")
    (pin "10")
    (pin "11")
    (pin "12")
    (pin "13")
    (pin "14")
    (pin "15")
    (pin "16")
    (pin "17")
    (pin "18")
    (pin "2")
    (pin "3")
    (pin "4")
    (pin "5")
    (pin "6")
    (pin "7")
    (pin "8")
    (pin "9")
    (instances
      (project "data-center-rdimm-ddr4-tester"
        (path ""
          (reference "U2") (unit 1)
        )
      )
    )
  )

  (symbol (lib_id "antmicroCapacitors0603:C_22u_0603") (at 163.83 67.945 270) (unit 1)
    (in_bom yes) (on_board yes) (dnp no)
    (property "Reference" "C159" (at 164.465 68.58 90)
      (effects (font (size 1.524 1.524)) (justify left))
    )
    (property "Value" "C_22u_0603" (at 153.67 88.265 0)
      (effects (font (size 1.27 1.27) (thickness 0.15)) (justify left bottom) hide)
    )
    (property "Footprint" "antmicro-footprints:C_0603_1608Metric" (at 151.13 88.265 0)
      (effects (font (size 1.27 1.27) (thickness 0.15)) (justify left bottom) hide)
    )
    (property "Datasheet" " " (at 148.59 88.265 0)
      (effects (font (size 1.27 1.27) (thickness 0.15)) (justify left bottom) hide)
    )
    (property "Manufacturer" "Murata" (at 143.51 88.265 0)
      (effects (font (size 1.27 1.27) (thickness 0.15)) (justify left bottom) hide)
    )
    (property "MPN" "GRM188R60J226MEA0D" (at 146.05 88.265 0)
      (effects (font (size 1.27 1.27) (thickness 0.15)) (justify left bottom) hide)
    )
    (property "Val" "22u" (at 164.465 72.39 90)
      (effects (font (size 1.27 1.27) (thickness 0.15)) (justify left))
    )
    (property "License" "Apache-2.0" (at 140.97 88.265 0)
      (effects (font (size 1.27 1.27) (thickness 0.15)) (justify left bottom) hide)
    )
    (property "Author" "Antmicro" (at 138.43 88.265 0)
      (effects (font (size 1.27 1.27) (thickness 0.15)) (justify left bottom) hide)
    )
    (property "Voltage" "" (at 135.89 88.265 0)
      (effects (font (size 1.27 1.27)) (justify left bottom) hide)
    )
    (property "Dielectric" "" (at 133.35 88.265 0)
      (effects (font (size 1.27 1.27)) (justify left bottom) hide)
    )
    (pin "1")
    (pin "2")
    (instances
      (project "data-center-rdimm-ddr4-tester"
        (path ""
          (reference "C159") (unit 1)
        )
      )
    )
  )

  (symbol (lib_id "antmicropower:GND") (at 163.83 73.025 0) (unit 1)
    (in_bom yes) (on_board yes) (dnp no) (fields_autoplaced)
    (property "Reference" "#PWR0147" (at 163.83 79.375 0)
      (effects (font (size 1.27 1.27)) hide)
    )
    (property "Value" "GND" (at 163.83 78.105 0)
      (effects (font (size 1.27 1.27)))
    )
    (property "Footprint" "" (at 163.83 73.025 0)
      (effects (font (size 1.27 1.27)) hide)
    )
    (property "Datasheet" "" (at 163.83 73.025 0)
      (effects (font (size 1.27 1.27)) hide)
    )
    (property "Author" "Antmicro" (at 172.72 80.645 0)
      (effects (font (size 1.27 1.27) (thickness 0.15)) (justify left bottom) hide)
    )
    (property "License" "Apache-2.0" (at 172.72 83.185 0)
      (effects (font (size 1.27 1.27) (thickness 0.15)) (justify left bottom) hide)
    )
    (pin "1")
    (instances
      (project "data-center-rdimm-ddr4-tester"
        (path ""
          (reference "#PWR0147") (unit 1)
        )
      )
    )
  )

  (symbol (lib_id "antmicroResistors0402:R_10k2_0402") (at 125.095 157.48 270) (unit 1)
    (in_bom yes) (on_board yes) (dnp no) (fields_autoplaced)
    (property "Reference" "R128" (at 127.635 158.75 90)
      (effects (font (size 1.524 1.524)) (justify left))
    )
    (property "Value" "R_10k2_0402" (at 112.395 177.8 0)
      (effects (font (size 1.27 1.27) (thickness 0.15)) (justify left bottom) hide)
    )
    (property "Footprint" "antmicro-footprints:R_0402_1005Metric" (at 109.855 177.8 0)
      (effects (font (size 1.27 1.27) (thickness 0.15)) (justify left bottom) hide)
    )
    (property "Datasheet" "https://www.bourns.com/docs/product-datasheets/cr.pdf" (at 107.315 177.8 0)
      (effects (font (size 1.27 1.27) (thickness 0.15)) (justify left bottom) hide)
    )
    (property "Manufacturer" "Bourns" (at 102.235 177.8 0)
      (effects (font (size 1.27 1.27) (thickness 0.15)) (justify left bottom) hide)
    )
    (property "MPN" "CR0402-FX-1022GLF" (at 104.775 177.8 0)
      (effects (font (size 1.27 1.27) (thickness 0.15)) (justify left bottom) hide)
    )
    (property "Val" "10k2" (at 127.635 161.9249 90)
      (effects (font (size 1.27 1.27) (thickness 0.15)) (justify left))
    )
    (property "License" "Apache-2.0" (at 99.695 177.8 0)
      (effects (font (size 1.27 1.27) (thickness 0.15)) (justify left bottom) hide)
    )
    (property "Author" "Antmicro" (at 97.155 177.8 0)
      (effects (font (size 1.27 1.27) (thickness 0.15)) (justify left bottom) hide)
    )
    (property "Tolerance" "1%" (at 114.935 177.8 0)
      (effects (font (size 1.27 1.27)) (justify left bottom) hide)
    )
    (pin "1")
    (pin "2")
    (instances
      (project "data-center-rdimm-ddr4-tester"
        (path ""
          (reference "R128") (unit 1)
        )
      )
    )
  )

  (symbol (lib_id "antmicroTestPoints:TP_1mm_SMD") (at 279.4 91.44 0) (unit 1)
    (in_bom yes) (on_board yes) (dnp no) (fields_autoplaced)
    (property "Reference" "PHY1" (at 284.48 91.4399 0)
      (effects (font (size 1.27 1.27)) (justify left))
    )
    (property "Value" "TP_1mm_SMD" (at 294.64 99.06 0)
      (effects (font (size 1.27 1.27) (thickness 0.15)) (justify left bottom) hide)
    )
    (property "Footprint" "antmicro-footprints:TP_SMD_1mm" (at 294.64 101.6 0)
      (effects (font (size 1.27 1.27) (thickness 0.15)) (justify left bottom) hide)
    )
    (property "Datasheet" "" (at 294.64 104.14 0)
      (effects (font (size 1.27 1.27) (thickness 0.15)) (justify left bottom) hide)
    )
    (property "MPN" "" (at 279.4 91.44 0)
      (effects (font (size 1.27 1.27)) hide)
    )
    (property "Manufacturer" "" (at 279.4 91.44 0)
      (effects (font (size 1.27 1.27)) hide)
    )
    (property "Author" "Antmicro" (at 294.64 106.68 0)
      (effects (font (size 1.27 1.27) (thickness 0.15)) (justify left bottom) hide)
    )
    (property "License" "Apache-2.0" (at 294.64 109.22 0)
      (effects (font (size 1.27 1.27) (thickness 0.15)) (justify left bottom) hide)
    )
    (pin "1")
    (instances
      (project "data-center-rdimm-ddr4-tester"
        (path ""
          (reference "PHY1") (unit 1)
        )
      )
    )
  )

  (symbol (lib_id "antmicroTestPoints:TP_1mm_SMD") (at 300.355 90.17 0) (unit 1)
    (in_bom yes) (on_board yes) (dnp no) (fields_autoplaced)
    (property "Reference" "VIN1" (at 306.07 90.1699 0)
      (effects (font (size 1.27 1.27)) (justify left))
    )
    (property "Value" "TP_1mm_SMD" (at 315.595 97.79 0)
      (effects (font (size 1.27 1.27) (thickness 0.15)) (justify left bottom) hide)
    )
    (property "Footprint" "antmicro-footprints:TP_SMD_1mm" (at 315.595 100.33 0)
      (effects (font (size 1.27 1.27) (thickness 0.15)) (justify left bottom) hide)
    )
    (property "Datasheet" "" (at 315.595 102.87 0)
      (effects (font (size 1.27 1.27) (thickness 0.15)) (justify left bottom) hide)
    )
    (property "MPN" "" (at 300.355 90.17 0)
      (effects (font (size 1.27 1.27)) hide)
    )
    (property "Manufacturer" "" (at 300.355 90.17 0)
      (effects (font (size 1.27 1.27)) hide)
    )
    (property "Author" "Antmicro" (at 315.595 105.41 0)
      (effects (font (size 1.27 1.27) (thickness 0.15)) (justify left bottom) hide)
    )
    (property "License" "Apache-2.0" (at 315.595 107.95 0)
      (effects (font (size 1.27 1.27) (thickness 0.15)) (justify left bottom) hide)
    )
    (pin "1")
    (instances
      (project "data-center-rdimm-ddr4-tester"
        (path ""
          (reference "VIN1") (unit 1)
        )
      )
    )
  )

  (symbol (lib_id "data-center-rdimm-ddr4-tester:AP62301WU-7") (at 218.44 130.175 0) (unit 1)
    (in_bom yes) (on_board yes) (dnp no)
    (property "Reference" "U9" (at 228.6 113.665 0)
      (effects (font (size 1.27 1.27)))
    )
    (property "Value" "AP62301WU-7" (at 228.6 116.205 0)
      (effects (font (size 1.27 1.27) (thickness 0.15)))
    )
    (property "Footprint" "data-center-rdimm-ddr4-tester-footprints:AP62301WU-7-TSOT23-6" (at 254 127.635 0)
      (effects (font (size 1.27 1.27) (thickness 0.15)) (justify left bottom) hide)
    )
    (property "Datasheet" "https://www.diodes.com/assets/Datasheets/AP62300_AP62301_AP62300T.pdf" (at 254 130.175 0)
      (effects (font (size 1.27 1.27) (thickness 0.15)) (justify left bottom) hide)
    )
    (property "MPN" "AP62301WU-7" (at 254 132.715 0)
      (effects (font (size 1.27 1.27) (thickness 0.15)) (justify left bottom) hide)
    )
    (property "Manufacturer" "Diodes Incorporated" (at 254 135.255 0)
      (effects (font (size 1.27 1.27) (thickness 0.15)) (justify left bottom) hide)
    )
    (property "Author" "Antmicro" (at 254 137.795 0)
      (effects (font (size 1.27 1.27) (thickness 0.15)) (justify left bottom) hide)
    )
    (property "License" "Apache-2.0" (at 254 140.335 0)
      (effects (font (size 1.27 1.27) (thickness 0.15)) (justify left bottom) hide)
    )
    (pin "1")
    (pin "2")
    (pin "3")
    (pin "4")
    (pin "5")
    (pin "6")
    (instances
      (project "data-center-rdimm-ddr4-tester"
        (path ""
          (reference "U9") (unit 1)
        )
      )
    )
  )

  (symbol (lib_id "data-center-rdimm-ddr4-tester:L_1u5_6A_1716") (at 248.285 120.015 0) (unit 1)
    (in_bom yes) (on_board yes) (dnp no) (fields_autoplaced)
    (property "Reference" "L5" (at 250.825 114.3 0)
      (effects (font (size 1.524 1.524)))
    )
    (property "Value" "L_1u5_6A_1716" (at 263.525 125.095 0)
      (effects (font (size 1.27 1.27) (thickness 0.15)) (justify left bottom) hide)
    )
    (property "Footprint" "data-center-rdimm-ddr4-tester-footprints:L_1716_4441Metric" (at 263.525 130.175 0)
      (effects (font (size 1.27 1.27) (thickness 0.15)) (justify left bottom) hide)
    )
    (property "Datasheet" "https://www.mouser.pl/datasheet/2/54/srp0420-1838509.pdf" (at 263.525 132.715 0)
      (effects (font (size 1.27 1.27) (thickness 0.15)) (justify left bottom) hide)
    )
    (property "Manufacturer" "Bourns" (at 263.525 137.795 0)
      (effects (font (size 1.27 1.27) (thickness 0.15)) (justify left bottom) hide)
    )
    (property "MPN" "SRP0420-1R5K" (at 263.525 135.255 0)
      (effects (font (size 1.27 1.27) (thickness 0.15)) (justify left bottom) hide)
    )
    (property "MaxCur" "6A" (at 263.525 140.335 0)
      (effects (font (size 1.27 1.27) (thickness 0.15)) (justify left bottom) hide)
    )
    (property "Size" "4.40x4.10" (at 263.525 142.875 0)
      (effects (font (size 1.27 1.27) (thickness 0.15)) (justify left bottom) hide)
    )
    (property "Val" "1u5/6A" (at 250.825 116.84 0)
      (effects (font (size 1.27 1.27) (thickness 0.15)))
    )
    (property "Author" "Antmicro" (at 263.525 145.415 0)
      (effects (font (size 1.27 1.27) (thickness 0.15)) (justify left bottom) hide)
    )
    (property "License" "Apache-2.0" (at 263.525 147.955 0)
      (effects (font (size 1.27 1.27) (thickness 0.15)) (justify left bottom) hide)
    )
    (pin "1")
    (pin "2")
    (instances
      (project "data-center-rdimm-ddr4-tester"
        (path ""
          (reference "L5") (unit 1)
        )
      )
    )
  )

  (symbol (lib_id "antmicroResistors0402:R_31k6_0402") (at 255.905 123.19 270) (unit 1)
    (in_bom yes) (on_board yes) (dnp no) (fields_autoplaced)
    (property "Reference" "R49" (at 258.445 124.46 90)
      (effects (font (size 1.524 1.524)) (justify left))
    )
    (property "Value" "R_31k6_0402" (at 243.205 143.51 0)
      (effects (font (size 1.27 1.27) (thickness 0.15)) (justify left bottom) hide)
    )
    (property "Footprint" "antmicro-footprints:R_0402_1005Metric" (at 240.665 143.51 0)
      (effects (font (size 1.27 1.27) (thickness 0.15)) (justify left bottom) hide)
    )
    (property "Datasheet" "https://www.bourns.com/docs/product-datasheets/cr.pdf" (at 238.125 143.51 0)
      (effects (font (size 1.27 1.27) (thickness 0.15)) (justify left bottom) hide)
    )
    (property "Manufacturer" "Bourns" (at 233.045 143.51 0)
      (effects (font (size 1.27 1.27) (thickness 0.15)) (justify left bottom) hide)
    )
    (property "MPN" "CR0402-FX-3162GLF" (at 235.585 143.51 0)
      (effects (font (size 1.27 1.27) (thickness 0.15)) (justify left bottom) hide)
    )
    (property "Val" "31k6" (at 258.445 127.6349 90)
      (effects (font (size 1.27 1.27) (thickness 0.15)) (justify left))
    )
    (property "License" "Apache-2.0" (at 230.505 143.51 0)
      (effects (font (size 1.27 1.27) (thickness 0.15)) (justify left bottom) hide)
    )
    (property "Author" "Antmicro" (at 227.965 143.51 0)
      (effects (font (size 1.27 1.27) (thickness 0.15)) (justify left bottom) hide)
    )
    (property "Tolerance" "1%" (at 245.745 143.51 0)
      (effects (font (size 1.27 1.27)) (justify left bottom) hide)
    )
    (pin "1")
    (pin "2")
    (instances
      (project "data-center-rdimm-ddr4-tester"
        (path ""
          (reference "R49") (unit 1)
        )
      )
    )
  )

  (symbol (lib_id "antmicropower:GND") (at 280.035 31.75 0) (unit 1)
    (in_bom yes) (on_board yes) (dnp no) (fields_autoplaced)
    (property "Reference" "#PWR023" (at 280.035 38.1 0)
      (effects (font (size 1.27 1.27)) hide)
    )
    (property "Value" "GND" (at 280.035 36.83 0)
      (effects (font (size 1.27 1.27)))
    )
    (property "Footprint" "" (at 280.035 31.75 0)
      (effects (font (size 1.27 1.27)) hide)
    )
    (property "Datasheet" "" (at 280.035 31.75 0)
      (effects (font (size 1.27 1.27)) hide)
    )
    (property "Author" "Antmicro" (at 288.925 39.37 0)
      (effects (font (size 1.27 1.27) (thickness 0.15)) (justify left bottom) hide)
    )
    (property "License" "Apache-2.0" (at 288.925 41.91 0)
      (effects (font (size 1.27 1.27) (thickness 0.15)) (justify left bottom) hide)
    )
    (pin "1")
    (instances
      (project "data-center-rdimm-ddr4-tester"
        (path ""
          (reference "#PWR023") (unit 1)
        )
      )
    )
  )

  (symbol (lib_id "antmicropower:GND") (at 274.32 58.42 0) (unit 1)
    (in_bom yes) (on_board yes) (dnp no) (fields_autoplaced)
    (property "Reference" "#PWR021" (at 274.32 64.77 0)
      (effects (font (size 1.27 1.27)) hide)
    )
    (property "Value" "GND" (at 274.32 63.5 0)
      (effects (font (size 1.27 1.27)))
    )
    (property "Footprint" "" (at 274.32 58.42 0)
      (effects (font (size 1.27 1.27)) hide)
    )
    (property "Datasheet" "" (at 274.32 58.42 0)
      (effects (font (size 1.27 1.27)) hide)
    )
    (property "Author" "Antmicro" (at 283.21 66.04 0)
      (effects (font (size 1.27 1.27) (thickness 0.15)) (justify left bottom) hide)
    )
    (property "License" "Apache-2.0" (at 283.21 68.58 0)
      (effects (font (size 1.27 1.27) (thickness 0.15)) (justify left bottom) hide)
    )
    (pin "1")
    (instances
      (project "data-center-rdimm-ddr4-tester"
        (path ""
          (reference "#PWR021") (unit 1)
        )
      )
    )
  )

  (symbol (lib_id "antmicropower:GND") (at 285.115 58.42 0) (unit 1)
    (in_bom yes) (on_board yes) (dnp no) (fields_autoplaced)
    (property "Reference" "#PWR020" (at 285.115 64.77 0)
      (effects (font (size 1.27 1.27)) hide)
    )
    (property "Value" "GND" (at 285.115 63.5 0)
      (effects (font (size 1.27 1.27)))
    )
    (property "Footprint" "" (at 285.115 58.42 0)
      (effects (font (size 1.27 1.27)) hide)
    )
    (property "Datasheet" "" (at 285.115 58.42 0)
      (effects (font (size 1.27 1.27)) hide)
    )
    (property "Author" "Antmicro" (at 294.005 66.04 0)
      (effects (font (size 1.27 1.27) (thickness 0.15)) (justify left bottom) hide)
    )
    (property "License" "Apache-2.0" (at 294.005 68.58 0)
      (effects (font (size 1.27 1.27) (thickness 0.15)) (justify left bottom) hide)
    )
    (pin "1")
    (instances
      (project "data-center-rdimm-ddr4-tester"
        (path ""
          (reference "#PWR020") (unit 1)
        )
      )
    )
  )

  (symbol (lib_id "antmicroTestPoints:TP_1mm_SMD") (at 279.4 96.52 0) (unit 1)
    (in_bom yes) (on_board yes) (dnp no) (fields_autoplaced)
    (property "Reference" "3V3" (at 284.48 96.5199 0)
      (effects (font (size 1.27 1.27)) (justify left))
    )
    (property "Value" "TP_1mm_SMD" (at 294.64 104.14 0)
      (effects (font (size 1.27 1.27) (thickness 0.15)) (justify left bottom) hide)
    )
    (property "Footprint" "antmicro-footprints:TP_SMD_1mm" (at 294.64 106.68 0)
      (effects (font (size 1.27 1.27) (thickness 0.15)) (justify left bottom) hide)
    )
    (property "Datasheet" "" (at 294.64 109.22 0)
      (effects (font (size 1.27 1.27) (thickness 0.15)) (justify left bottom) hide)
    )
    (property "MPN" "" (at 279.4 96.52 0)
      (effects (font (size 1.27 1.27)) hide)
    )
    (property "Manufacturer" "" (at 279.4 96.52 0)
      (effects (font (size 1.27 1.27)) hide)
    )
    (property "Author" "Antmicro" (at 294.64 111.76 0)
      (effects (font (size 1.27 1.27) (thickness 0.15)) (justify left bottom) hide)
    )
    (property "License" "Apache-2.0" (at 294.64 114.3 0)
      (effects (font (size 1.27 1.27) (thickness 0.15)) (justify left bottom) hide)
    )
    (pin "1")
    (instances
      (project "data-center-rdimm-ddr4-tester"
        (path ""
          (reference "3V3") (unit 1)
        )
      )
    )
  )

  (symbol (lib_id "antmicroPMICVoltageRegulatorsLinear:TPS54561QDPRRQ1") (at 67.945 132.08 0) (unit 1)
    (in_bom yes) (on_board yes) (dnp no) (fields_autoplaced)
    (property "Reference" "IC1" (at 80.645 123.19 0)
      (effects (font (size 1.524 1.524)))
    )
    (property "Value" "TPS54561QDPRRQ1" (at 80.645 127 0)
      (effects (font (size 1.27 1.27) (thickness 0.15)))
    )
    (property "Footprint" "antmicro-footprints:WSON-10-1EP_4x4mm_P0.8mm_EP2.6x3mm" (at 106.045 139.7 0)
      (effects (font (size 1.27 1.27) (thickness 0.15)) (justify left bottom) hide)
    )
    (property "Datasheet" "https://www.ti.com/lit/ds/symlink/tps54561-q1.pdf?ts=1678720110394&ref_url=https%253A%252F%252Fwww.google.com%252F" (at 106.045 142.24 0)
      (effects (font (size 1.27 1.27) (thickness 0.15)) (justify left bottom) hide)
    )
    (property "Manufacturer" "Texas Instruments" (at 106.045 144.78 0)
      (effects (font (size 1.27 1.27) (thickness 0.15)) (justify left bottom) hide)
    )
    (property "MPN" "TPS54561QDPRRQ1" (at 106.045 147.32 0)
      (effects (font (size 1.27 1.27) (thickness 0.15)) (justify left bottom) hide)
    )
    (property "Author" "Antmicro" (at 106.045 149.86 0)
      (effects (font (size 1.27 1.27) (thickness 0.15)) (justify left bottom) hide)
    )
    (property "License" "Apache-2.0" (at 106.045 152.4 0)
      (effects (font (size 1.27 1.27) (thickness 0.15)) (justify left bottom) hide)
    )
    (pin "1")
    (pin "10")
    (pin "11")
    (pin "2")
    (pin "3")
    (pin "4")
    (pin "5")
    (pin "6")
    (pin "7")
    (pin "8")
    (pin "9")
    (instances
      (project "data-center-rdimm-ddr4-tester"
        (path ""
          (reference "IC1") (unit 1)
        )
      )
    )
  )

  (symbol (lib_id "antmicroCapacitors0402:C_100n_0402") (at 100.965 134.62 0) (unit 1)
    (in_bom yes) (on_board yes) (dnp no)
    (property "Reference" "C178" (at 99.695 133.35 0)
      (effects (font (size 1.524 1.524)))
    )
    (property "Value" "C_100n_0402" (at 121.285 144.78 0)
      (effects (font (size 1.27 1.27) (thickness 0.15)) (justify left bottom) hide)
    )
    (property "Footprint" "antmicro-footprints:C_0402_1005Metric" (at 121.285 147.32 0)
      (effects (font (size 1.27 1.27) (thickness 0.15)) (justify left bottom) hide)
    )
    (property "Datasheet" "https://search.murata.co.jp/Ceramy/image/img/A01X/G101/ENG/GRM155R61H104KE14-01.pdf" (at 121.285 149.86 0)
      (effects (font (size 1.27 1.27) (thickness 0.15)) (justify left bottom) hide)
    )
    (property "Manufacturer" "Murata" (at 121.285 154.94 0)
      (effects (font (size 1.27 1.27) (thickness 0.15)) (justify left bottom) hide)
    )
    (property "MPN" "GRM155R61H104KE14D" (at 121.285 152.4 0)
      (effects (font (size 1.27 1.27) (thickness 0.15)) (justify left bottom) hide)
    )
    (property "Val" "100n" (at 106.68 133.35 0)
      (effects (font (size 1.27 1.27) (thickness 0.15)))
    )
    (property "License" "Apache-2.0" (at 121.285 157.48 0)
      (effects (font (size 1.27 1.27) (thickness 0.15)) (justify left bottom) hide)
    )
    (property "Author" "Antmicro" (at 121.285 160.02 0)
      (effects (font (size 1.27 1.27) (thickness 0.15)) (justify left bottom) hide)
    )
    (property "Voltage" "50V" (at 121.285 162.56 0)
      (effects (font (size 1.27 1.27)) (justify left bottom) hide)
    )
    (property "Dielectric" "X5R" (at 121.285 165.1 0)
      (effects (font (size 1.27 1.27)) (justify left bottom) hide)
    )
    (pin "1")
    (pin "2")
    (instances
      (project "data-center-rdimm-ddr4-tester"
        (path ""
          (reference "C178") (unit 1)
        )
      )
    )
  )

  (symbol (lib_id "antmicroResistors0402:R_49R9_0402") (at 125.095 143.51 270) (unit 1)
    (in_bom yes) (on_board yes) (dnp no) (fields_autoplaced)
    (property "Reference" "R126" (at 127.635 144.78 90)
      (effects (font (size 1.524 1.524)) (justify left))
    )
    (property "Value" "R_49R9_0402" (at 112.395 163.83 0)
      (effects (font (size 1.27 1.27) (thickness 0.15)) (justify left bottom) hide)
    )
    (property "Footprint" "antmicro-footprints:R_0402_1005Metric" (at 109.855 163.83 0)
      (effects (font (size 1.27 1.27) (thickness 0.15)) (justify left bottom) hide)
    )
    (property "Datasheet" "https://www.bourns.com/docs/product-datasheets/cr.pdf" (at 107.315 163.83 0)
      (effects (font (size 1.27 1.27) (thickness 0.15)) (justify left bottom) hide)
    )
    (property "Manufacturer" "Bourns" (at 102.235 163.83 0)
      (effects (font (size 1.27 1.27) (thickness 0.15)) (justify left bottom) hide)
    )
    (property "MPN" "CR0402-FX-49R9GLF" (at 104.775 163.83 0)
      (effects (font (size 1.27 1.27) (thickness 0.15)) (justify left bottom) hide)
    )
    (property "Val" "49R9" (at 127.635 147.9549 90)
      (effects (font (size 1.27 1.27) (thickness 0.15)) (justify left))
    )
    (property "License" "Apache-2.0" (at 99.695 163.83 0)
      (effects (font (size 1.27 1.27) (thickness 0.15)) (justify left bottom) hide)
    )
    (property "Author" "Antmicro" (at 97.155 163.83 0)
      (effects (font (size 1.27 1.27) (thickness 0.15)) (justify left bottom) hide)
    )
    (property "Tolerance" "1%" (at 114.935 163.83 0)
      (effects (font (size 1.27 1.27)) (justify left bottom) hide)
    )
    (pin "1")
    (pin "2")
    (instances
      (project "data-center-rdimm-ddr4-tester"
        (path ""
          (reference "R126") (unit 1)
        )
      )
    )
  )

  (symbol (lib_id "antmicroResistors0402:R_53k6_0402") (at 125.095 149.86 270) (unit 1)
    (in_bom yes) (on_board yes) (dnp no) (fields_autoplaced)
    (property "Reference" "R127" (at 127.635 151.13 90)
      (effects (font (size 1.524 1.524)) (justify left))
    )
    (property "Value" "R_53k6_0402" (at 112.395 170.18 0)
      (effects (font (size 1.27 1.27) (thickness 0.15)) (justify left bottom) hide)
    )
    (property "Footprint" "antmicro-footprints:R_0402_1005Metric" (at 109.855 170.18 0)
      (effects (font (size 1.27 1.27) (thickness 0.15)) (justify left bottom) hide)
    )
    (property "Datasheet" "https://www.bourns.com/docs/product-datasheets/cr.pdf" (at 107.315 170.18 0)
      (effects (font (size 1.27 1.27) (thickness 0.15)) (justify left bottom) hide)
    )
    (property "Manufacturer" "Bourns" (at 102.235 170.18 0)
      (effects (font (size 1.27 1.27) (thickness 0.15)) (justify left bottom) hide)
    )
    (property "MPN" "CR0402-FX-5362GLF" (at 104.775 170.18 0)
      (effects (font (size 1.27 1.27) (thickness 0.15)) (justify left bottom) hide)
    )
    (property "Val" "53k6" (at 127.635 154.3049 90)
      (effects (font (size 1.27 1.27) (thickness 0.15)) (justify left))
    )
    (property "License" "Apache-2.0" (at 99.695 170.18 0)
      (effects (font (size 1.27 1.27) (thickness 0.15)) (justify left bottom) hide)
    )
    (property "Author" "Antmicro" (at 97.155 170.18 0)
      (effects (font (size 1.27 1.27) (thickness 0.15)) (justify left bottom) hide)
    )
    (property "Tolerance" "1%" (at 114.935 170.18 0)
      (effects (font (size 1.27 1.27)) (justify left bottom) hide)
    )
    (pin "1")
    (pin "2")
    (instances
      (project "data-center-rdimm-ddr4-tester"
        (path ""
          (reference "R127") (unit 1)
        )
      )
    )
  )

  (symbol (lib_id "antmicroDiodesRectifiersSingle:PDS760") (at 319.405 233.045 0) (unit 1)
    (in_bom yes) (on_board yes) (dnp no)
    (property "Reference" "D11" (at 323.215 227.965 0)
      (effects (font (size 1.524 1.524)))
    )
    (property "Value" "PDS760" (at 323.215 230.505 0)
      (effects (font (size 1.27 1.27) (thickness 0.15)))
    )
    (property "Footprint" "antmicro-footprints:PowerDI5" (at 342.265 243.205 0)
      (effects (font (size 1.27 1.27) (thickness 0.15)) (justify left bottom) hide)
    )
    (property "Datasheet" "https://www.diodes.com/assets/Datasheets/ds30470.pdf" (at 342.265 245.745 0)
      (effects (font (size 1.27 1.27) (thickness 0.15)) (justify left bottom) hide)
    )
    (property "Manufacturer" "Diodes Incorporated" (at 342.265 248.285 0)
      (effects (font (size 1.27 1.27) (thickness 0.15)) (justify left bottom) hide)
    )
    (property "MPN" "PDS760-13" (at 342.265 250.825 0)
      (effects (font (size 1.27 1.27) (thickness 0.15)) (justify left bottom) hide)
    )
    (property "Author" "Antmicro" (at 342.265 253.365 0)
      (effects (font (size 1.27 1.27) (thickness 0.15)) (justify left bottom) hide)
    )
    (property "License" "Apache-2.0" (at 342.265 255.905 0)
      (effects (font (size 1.27 1.27) (thickness 0.15)) (justify left bottom) hide)
    )
    (pin "A")
    (pin "C")
    (instances
      (project "data-center-rdimm-ddr4-tester"
        (path ""
          (reference "D11") (unit 1)
        )
      )
    )
  )

  (symbol (lib_id "antmicroCapacitors0603:C_47u_0603") (at 145.415 140.97 270) (unit 1)
    (in_bom yes) (on_board yes) (dnp no)
    (property "Reference" "C182" (at 146.05 141.605 90)
      (effects (font (size 1.524 1.524)) (justify left))
    )
    (property "Value" "C_47u_0603" (at 135.255 161.29 0)
      (effects (font (size 1.27 1.27) (thickness 0.15)) (justify left bottom) hide)
    )
    (property "Footprint" "antmicro-footprints:C_0603_1608Metric" (at 132.715 161.29 0)
      (effects (font (size 1.27 1.27) (thickness 0.15)) (justify left bottom) hide)
    )
    (property "Datasheet" " " (at 130.175 161.29 0)
      (effects (font (size 1.27 1.27) (thickness 0.15)) (justify left bottom) hide)
    )
    (property "Manufacturer" "Murata" (at 125.095 161.29 0)
      (effects (font (size 1.27 1.27) (thickness 0.15)) (justify left bottom) hide)
    )
    (property "MPN" "GRM188R60J476ME15D" (at 127.635 161.29 0)
      (effects (font (size 1.27 1.27) (thickness 0.15)) (justify left bottom) hide)
    )
    (property "Val" "47u" (at 146.05 145.415 90)
      (effects (font (size 1.27 1.27) (thickness 0.15)) (justify left))
    )
    (property "License" "Apache-2.0" (at 122.555 161.29 0)
      (effects (font (size 1.27 1.27) (thickness 0.15)) (justify left bottom) hide)
    )
    (property "Author" "Antmicro" (at 120.015 161.29 0)
      (effects (font (size 1.27 1.27) (thickness 0.15)) (justify left bottom) hide)
    )
    (property "Voltage" "" (at 117.475 161.29 0)
      (effects (font (size 1.27 1.27)) (justify left bottom) hide)
    )
    (property "Dielectric" "" (at 114.935 161.29 0)
      (effects (font (size 1.27 1.27)) (justify left bottom) hide)
    )
    (pin "1")
    (pin "2")
    (instances
      (project "data-center-rdimm-ddr4-tester"
        (path ""
          (reference "C182") (unit 1)
        )
      )
    )
  )

  (symbol (lib_id "antmicropower:GND") (at 145.415 148.59 0) (unit 1)
    (in_bom yes) (on_board yes) (dnp no) (fields_autoplaced)
    (property "Reference" "#PWR0184" (at 145.415 154.94 0)
      (effects (font (size 1.27 1.27)) hide)
    )
    (property "Value" "GND" (at 145.415 153.67 0)
      (effects (font (size 1.27 1.27)))
    )
    (property "Footprint" "" (at 145.415 148.59 0)
      (effects (font (size 1.27 1.27)) hide)
    )
    (property "Datasheet" "" (at 145.415 148.59 0)
      (effects (font (size 1.27 1.27)) hide)
    )
    (property "Author" "Antmicro" (at 154.305 156.21 0)
      (effects (font (size 1.27 1.27) (thickness 0.15)) (justify left bottom) hide)
    )
    (property "License" "Apache-2.0" (at 154.305 158.75 0)
      (effects (font (size 1.27 1.27) (thickness 0.15)) (justify left bottom) hide)
    )
    (pin "1")
    (instances
      (project "data-center-rdimm-ddr4-tester"
        (path ""
          (reference "#PWR0184") (unit 1)
        )
      )
    )
  )

  (symbol (lib_id "antmicropower:GND") (at 34.29 121.285 0) (unit 1)
    (in_bom yes) (on_board yes) (dnp no) (fields_autoplaced)
    (property "Reference" "#PWR0190" (at 34.29 127.635 0)
      (effects (font (size 1.27 1.27)) hide)
    )
    (property "Value" "GND" (at 34.29 126.365 0)
      (effects (font (size 1.27 1.27)))
    )
    (property "Footprint" "" (at 34.29 121.285 0)
      (effects (font (size 1.27 1.27)) hide)
    )
    (property "Datasheet" "" (at 34.29 121.285 0)
      (effects (font (size 1.27 1.27)) hide)
    )
    (property "Author" "Antmicro" (at 43.18 128.905 0)
      (effects (font (size 1.27 1.27) (thickness 0.15)) (justify left bottom) hide)
    )
    (property "License" "Apache-2.0" (at 43.18 131.445 0)
      (effects (font (size 1.27 1.27) (thickness 0.15)) (justify left bottom) hide)
    )
    (pin "1")
    (instances
      (project "data-center-rdimm-ddr4-tester"
        (path ""
          (reference "#PWR0190") (unit 1)
        )
      )
    )
  )

  (symbol (lib_id "antmicropower:GND") (at 45.72 121.285 0) (unit 1)
    (in_bom yes) (on_board yes) (dnp no) (fields_autoplaced)
    (property "Reference" "#PWR0191" (at 45.72 127.635 0)
      (effects (font (size 1.27 1.27)) hide)
    )
    (property "Value" "GND" (at 45.72 126.365 0)
      (effects (font (size 1.27 1.27)))
    )
    (property "Footprint" "" (at 45.72 121.285 0)
      (effects (font (size 1.27 1.27)) hide)
    )
    (property "Datasheet" "" (at 45.72 121.285 0)
      (effects (font (size 1.27 1.27)) hide)
    )
    (property "Author" "Antmicro" (at 54.61 128.905 0)
      (effects (font (size 1.27 1.27) (thickness 0.15)) (justify left bottom) hide)
    )
    (property "License" "Apache-2.0" (at 54.61 131.445 0)
      (effects (font (size 1.27 1.27) (thickness 0.15)) (justify left bottom) hide)
    )
    (pin "1")
    (instances
      (project "data-center-rdimm-ddr4-tester"
        (path ""
          (reference "#PWR0191") (unit 1)
        )
      )
    )
  )

  (symbol (lib_id "antmicroCapacitors0402:C_10n_0402") (at 60.325 142.24 0) (unit 1)
    (in_bom yes) (on_board yes) (dnp no)
    (property "Reference" "C174" (at 59.055 140.97 0)
      (effects (font (size 1.524 1.524)))
    )
    (property "Value" "C_10n_0402" (at 80.645 152.4 0)
      (effects (font (size 1.27 1.27) (thickness 0.15)) (justify left bottom) hide)
    )
    (property "Footprint" "antmicro-footprints:C_0402_1005Metric" (at 80.645 154.94 0)
      (effects (font (size 1.27 1.27) (thickness 0.15)) (justify left bottom) hide)
    )
    (property "Datasheet" "https://search.murata.co.jp/Ceramy/image/img/A01X/G101/ENG/GRM155R71H103KA88-01.pdf" (at 80.645 157.48 0)
      (effects (font (size 1.27 1.27) (thickness 0.15)) (justify left bottom) hide)
    )
    (property "Manufacturer" "Murata" (at 80.645 162.56 0)
      (effects (font (size 1.27 1.27) (thickness 0.15)) (justify left bottom) hide)
    )
    (property "MPN" "GRM155R71H103KA88D" (at 80.645 160.02 0)
      (effects (font (size 1.27 1.27) (thickness 0.15)) (justify left bottom) hide)
    )
    (property "Val" "10n" (at 66.04 140.97 0)
      (effects (font (size 1.27 1.27) (thickness 0.15)))
    )
    (property "License" "Apache-2.0" (at 80.645 165.1 0)
      (effects (font (size 1.27 1.27) (thickness 0.15)) (justify left bottom) hide)
    )
    (property "Author" "Antmicro" (at 80.645 167.64 0)
      (effects (font (size 1.27 1.27) (thickness 0.15)) (justify left bottom) hide)
    )
    (property "Voltage" "50V" (at 80.645 170.18 0)
      (effects (font (size 1.27 1.27)) (justify left bottom) hide)
    )
    (property "Dielectric" "X7R" (at 80.645 172.72 0)
      (effects (font (size 1.27 1.27)) (justify left bottom) hide)
    )
    (pin "1")
    (pin "2")
    (instances
      (project "data-center-rdimm-ddr4-tester"
        (path ""
          (reference "C174") (unit 1)
        )
      )
    )
  )

  (symbol (lib_id "antmicroResistors0402:R_243k_0402") (at 50.8 139.7 0) (unit 1)
    (in_bom yes) (on_board yes) (dnp no)
    (property "Reference" "R116" (at 48.26 138.43 0)
      (effects (font (size 1.524 1.524)))
    )
    (property "Value" "R_243k_0402" (at 71.12 152.4 0)
      (effects (font (size 1.27 1.27) (thickness 0.15)) (justify left bottom) hide)
    )
    (property "Footprint" "antmicro-footprints:R_0402_1005Metric" (at 71.12 154.94 0)
      (effects (font (size 1.27 1.27) (thickness 0.15)) (justify left bottom) hide)
    )
    (property "Datasheet" "https://www.bourns.com/docs/product-datasheets/cr.pdf" (at 71.12 157.48 0)
      (effects (font (size 1.27 1.27) (thickness 0.15)) (justify left bottom) hide)
    )
    (property "Manufacturer" "Bourns" (at 71.12 162.56 0)
      (effects (font (size 1.27 1.27) (thickness 0.15)) (justify left bottom) hide)
    )
    (property "MPN" "CR0402-FX-2433GLF" (at 71.12 160.02 0)
      (effects (font (size 1.27 1.27) (thickness 0.15)) (justify left bottom) hide)
    )
    (property "Val" "243k" (at 57.785 138.43 0)
      (effects (font (size 1.27 1.27) (thickness 0.15)))
    )
    (property "License" "Apache-2.0" (at 71.12 165.1 0)
      (effects (font (size 1.27 1.27) (thickness 0.15)) (justify left bottom) hide)
    )
    (property "Author" "Antmicro" (at 71.12 167.64 0)
      (effects (font (size 1.27 1.27) (thickness 0.15)) (justify left bottom) hide)
    )
    (property "Tolerance" "1%" (at 71.12 149.86 0)
      (effects (font (size 1.27 1.27)) (justify left bottom) hide)
    )
    (pin "1")
    (pin "2")
    (instances
      (project "data-center-rdimm-ddr4-tester"
        (path ""
          (reference "R116") (unit 1)
        )
      )
    )
  )

  (symbol (lib_id "antmicropower:GND") (at 46.355 144.78 0) (unit 1)
    (in_bom yes) (on_board yes) (dnp no) (fields_autoplaced)
    (property "Reference" "#PWR0192" (at 46.355 151.13 0)
      (effects (font (size 1.27 1.27)) hide)
    )
    (property "Value" "GND" (at 46.355 149.86 0)
      (effects (font (size 1.27 1.27)))
    )
    (property "Footprint" "" (at 46.355 144.78 0)
      (effects (font (size 1.27 1.27)) hide)
    )
    (property "Datasheet" "" (at 46.355 144.78 0)
      (effects (font (size 1.27 1.27)) hide)
    )
    (property "Author" "Antmicro" (at 55.245 152.4 0)
      (effects (font (size 1.27 1.27) (thickness 0.15)) (justify left bottom) hide)
    )
    (property "License" "Apache-2.0" (at 55.245 154.94 0)
      (effects (font (size 1.27 1.27) (thickness 0.15)) (justify left bottom) hide)
    )
    (pin "1")
    (instances
      (project "data-center-rdimm-ddr4-tester"
        (path ""
          (reference "#PWR0192") (unit 1)
        )
      )
    )
  )

  (symbol (lib_id "antmicroResistors0402:R_10k_0402") (at 311.15 31.115 270) (unit 1)
    (in_bom yes) (on_board yes) (dnp no)
    (property "Reference" "R86" (at 311.785 30.48 90)
      (effects (font (size 1.524 1.524)) (justify left))
    )
    (property "Value" "R_10k_0402" (at 298.45 51.435 0)
      (effects (font (size 1.27 1.27) (thickness 0.15)) (justify left bottom) hide)
    )
    (property "Footprint" "antmicro-footprints:R_0402_1005Metric" (at 295.91 51.435 0)
      (effects (font (size 1.27 1.27) (thickness 0.15)) (justify left bottom) hide)
    )
    (property "Datasheet" "https://www.bourns.com/docs/product-datasheets/cr.pdf" (at 293.37 51.435 0)
      (effects (font (size 1.27 1.27) (thickness 0.15)) (justify left bottom) hide)
    )
    (property "Manufacturer" "Bourns" (at 288.29 51.435 0)
      (effects (font (size 1.27 1.27) (thickness 0.15)) (justify left bottom) hide)
    )
    (property "MPN" "CR0402-FX-1002GLF" (at 290.83 51.435 0)
      (effects (font (size 1.27 1.27) (thickness 0.15)) (justify left bottom) hide)
    )
    (property "Val" "10k" (at 311.785 36.83 90)
      (effects (font (size 1.27 1.27) (thickness 0.15)) (justify left))
    )
    (property "License" "Apache-2.0" (at 285.75 51.435 0)
      (effects (font (size 1.27 1.27) (thickness 0.15)) (justify left bottom) hide)
    )
    (property "Author" "Antmicro" (at 283.21 51.435 0)
      (effects (font (size 1.27 1.27) (thickness 0.15)) (justify left bottom) hide)
    )
    (property "Tolerance" "1%" (at 300.99 51.435 0)
      (effects (font (size 1.27 1.27)) (justify left bottom) hide)
    )
    (pin "1")
    (pin "2")
    (instances
      (project "data-center-rdimm-ddr4-tester"
        (path ""
          (reference "R86") (unit 1)
        )
      )
    )
  )

  (symbol (lib_id "antmicroResistors0402:R_10k_0402") (at 316.865 31.115 270) (unit 1)
    (in_bom yes) (on_board yes) (dnp no)
    (property "Reference" "R87" (at 317.5 30.48 90)
      (effects (font (size 1.524 1.524)) (justify left))
    )
    (property "Value" "R_10k_0402" (at 304.165 51.435 0)
      (effects (font (size 1.27 1.27) (thickness 0.15)) (justify left bottom) hide)
    )
    (property "Footprint" "antmicro-footprints:R_0402_1005Metric" (at 301.625 51.435 0)
      (effects (font (size 1.27 1.27) (thickness 0.15)) (justify left bottom) hide)
    )
    (property "Datasheet" "https://www.bourns.com/docs/product-datasheets/cr.pdf" (at 299.085 51.435 0)
      (effects (font (size 1.27 1.27) (thickness 0.15)) (justify left bottom) hide)
    )
    (property "Manufacturer" "Bourns" (at 294.005 51.435 0)
      (effects (font (size 1.27 1.27) (thickness 0.15)) (justify left bottom) hide)
    )
    (property "MPN" "CR0402-FX-1002GLF" (at 296.545 51.435 0)
      (effects (font (size 1.27 1.27) (thickness 0.15)) (justify left bottom) hide)
    )
    (property "Val" "10k" (at 317.5 36.83 90)
      (effects (font (size 1.27 1.27) (thickness 0.15)) (justify left))
    )
    (property "License" "Apache-2.0" (at 291.465 51.435 0)
      (effects (font (size 1.27 1.27) (thickness 0.15)) (justify left bottom) hide)
    )
    (property "Author" "Antmicro" (at 288.925 51.435 0)
      (effects (font (size 1.27 1.27) (thickness 0.15)) (justify left bottom) hide)
    )
    (property "Tolerance" "1%" (at 306.705 51.435 0)
      (effects (font (size 1.27 1.27)) (justify left bottom) hide)
    )
    (pin "1")
    (pin "2")
    (instances
      (project "data-center-rdimm-ddr4-tester"
        (path ""
          (reference "R87") (unit 1)
        )
      )
    )
  )

  (symbol (lib_id "antmicroResistors0402:R_10k_0402") (at 322.58 31.115 270) (unit 1)
    (in_bom yes) (on_board yes) (dnp no)
    (property "Reference" "R88" (at 323.215 30.48 90)
      (effects (font (size 1.524 1.524)) (justify left))
    )
    (property "Value" "R_10k_0402" (at 309.88 51.435 0)
      (effects (font (size 1.27 1.27) (thickness 0.15)) (justify left bottom) hide)
    )
    (property "Footprint" "antmicro-footprints:R_0402_1005Metric" (at 307.34 51.435 0)
      (effects (font (size 1.27 1.27) (thickness 0.15)) (justify left bottom) hide)
    )
    (property "Datasheet" "https://www.bourns.com/docs/product-datasheets/cr.pdf" (at 304.8 51.435 0)
      (effects (font (size 1.27 1.27) (thickness 0.15)) (justify left bottom) hide)
    )
    (property "Manufacturer" "Bourns" (at 299.72 51.435 0)
      (effects (font (size 1.27 1.27) (thickness 0.15)) (justify left bottom) hide)
    )
    (property "MPN" "CR0402-FX-1002GLF" (at 302.26 51.435 0)
      (effects (font (size 1.27 1.27) (thickness 0.15)) (justify left bottom) hide)
    )
    (property "Val" "10k" (at 323.215 36.83 90)
      (effects (font (size 1.27 1.27) (thickness 0.15)) (justify left))
    )
    (property "License" "Apache-2.0" (at 297.18 51.435 0)
      (effects (font (size 1.27 1.27) (thickness 0.15)) (justify left bottom) hide)
    )
    (property "Author" "Antmicro" (at 294.64 51.435 0)
      (effects (font (size 1.27 1.27) (thickness 0.15)) (justify left bottom) hide)
    )
    (property "Tolerance" "1%" (at 312.42 51.435 0)
      (effects (font (size 1.27 1.27)) (justify left bottom) hide)
    )
    (pin "1")
    (pin "2")
    (instances
      (project "data-center-rdimm-ddr4-tester"
        (path ""
          (reference "R88") (unit 1)
        )
      )
    )
  )

  (symbol (lib_id "antmicropower:GND") (at 318.135 245.745 0) (unit 1)
    (in_bom yes) (on_board yes) (dnp no) (fields_autoplaced)
    (property "Reference" "#PWR0208" (at 318.135 252.095 0)
      (effects (font (size 1.27 1.27)) hide)
    )
    (property "Value" "GND" (at 318.135 250.19 0)
      (effects (font (size 1.27 1.27)))
    )
    (property "Footprint" "" (at 318.135 245.745 0)
      (effects (font (size 1.27 1.27)) hide)
    )
    (property "Datasheet" "" (at 318.135 245.745 0)
      (effects (font (size 1.27 1.27)) hide)
    )
    (property "Author" "Antmicro" (at 327.025 253.365 0)
      (effects (font (size 1.27 1.27) (thickness 0.15)) (justify left bottom) hide)
    )
    (property "License" "Apache-2.0" (at 327.025 255.905 0)
      (effects (font (size 1.27 1.27) (thickness 0.15)) (justify left bottom) hide)
    )
    (pin "1")
    (instances
      (project "data-center-rdimm-ddr4-tester"
        (path ""
          (reference "#PWR0208") (unit 1)
        )
      )
    )
  )

  (symbol (lib_id "antmicroLEDIndicationDiscrete:LED_G_0603_KP-1608CGCK") (at 356.87 233.045 270) (unit 1)
    (in_bom yes) (on_board yes) (dnp no)
    (property "Reference" "PWR1" (at 354.965 235.585 90)
      (effects (font (size 1.524 1.524)) (justify right))
    )
    (property "Value" "LED_G_0603_KP-1608CGCK" (at 360.045 238.7599 90)
      (effects (font (size 1.27 1.27) (thickness 0.15)) (justify left) hide)
    )
    (property "Footprint" "antmicro-footprints:LED_0603_1608Metric_G" (at 346.71 255.905 0)
      (effects (font (size 1.27 1.27) (thickness 0.15)) (justify left bottom) hide)
    )
    (property "Datasheet" "http://www.farnell.com/datasheets/2045956.pdf" (at 344.17 255.905 0)
      (effects (font (size 1.27 1.27) (thickness 0.15)) (justify left bottom) hide)
    )
    (property "MPN" "KP-1608CGCK" (at 354.965 237.49 90)
      (effects (font (size 1.27 1.27) (thickness 0.15)) (justify right))
    )
    (property "Manufacturer" "Kingbright" (at 339.09 255.905 0)
      (effects (font (size 1.27 1.27) (thickness 0.15)) (justify left bottom) hide)
    )
    (property "Author" "Antmicro" (at 336.55 255.905 0)
      (effects (font (size 1.27 1.27) (thickness 0.15)) (justify left bottom) hide)
    )
    (property "License" "Apache-2.0" (at 334.01 255.905 0)
      (effects (font (size 1.27 1.27) (thickness 0.15)) (justify left bottom) hide)
    )
    (pin "1")
    (pin "2")
    (instances
      (project "data-center-rdimm-ddr4-tester"
        (path ""
          (reference "PWR1") (unit 1)
        )
      )
    )
  )

  (symbol (lib_id "antmicroResistors0402:R_330R_0402") (at 356.87 240.665 270) (unit 1)
    (in_bom yes) (on_board yes) (dnp no) (fields_autoplaced)
    (property "Reference" "R119" (at 354.965 241.935 90)
      (effects (font (size 1.524 1.524)) (justify right))
    )
    (property "Value" "R_330R_0402" (at 344.17 260.985 0)
      (effects (font (size 1.27 1.27) (thickness 0.15)) (justify left bottom) hide)
    )
    (property "Footprint" "antmicro-footprints:R_0402_1005Metric" (at 341.63 260.985 0)
      (effects (font (size 1.27 1.27) (thickness 0.15)) (justify left bottom) hide)
    )
    (property "Datasheet" "https://www.bourns.com/docs/product-datasheets/cr.pdf" (at 339.09 260.985 0)
      (effects (font (size 1.27 1.27) (thickness 0.15)) (justify left bottom) hide)
    )
    (property "Manufacturer" "Bourns" (at 334.01 260.985 0)
      (effects (font (size 1.27 1.27) (thickness 0.15)) (justify left bottom) hide)
    )
    (property "MPN" "CR0402-FX-3300GLF" (at 336.55 260.985 0)
      (effects (font (size 1.27 1.27) (thickness 0.15)) (justify left bottom) hide)
    )
    (property "Val" "330R" (at 354.965 245.1099 90)
      (effects (font (size 1.27 1.27) (thickness 0.15)) (justify right))
    )
    (property "License" "Apache-2.0" (at 331.47 260.985 0)
      (effects (font (size 1.27 1.27) (thickness 0.15)) (justify left bottom) hide)
    )
    (property "Author" "Antmicro" (at 328.93 260.985 0)
      (effects (font (size 1.27 1.27) (thickness 0.15)) (justify left bottom) hide)
    )
    (property "Tolerance" "1%" (at 346.71 260.985 0)
      (effects (font (size 1.27 1.27)) (justify left bottom) hide)
    )
    (pin "1")
    (pin "2")
    (instances
      (project "data-center-rdimm-ddr4-tester"
        (path ""
          (reference "R119") (unit 1)
        )
      )
    )
  )

  (symbol (lib_id "antmicropower:GND") (at 356.87 245.745 0) (unit 1)
    (in_bom yes) (on_board yes) (dnp no) (fields_autoplaced)
    (property "Reference" "#PWR0209" (at 356.87 252.095 0)
      (effects (font (size 1.27 1.27)) hide)
    )
    (property "Value" "GND" (at 356.87 250.825 0)
      (effects (font (size 1.27 1.27)))
    )
    (property "Footprint" "" (at 356.87 245.745 0)
      (effects (font (size 1.27 1.27)) hide)
    )
    (property "Datasheet" "" (at 356.87 245.745 0)
      (effects (font (size 1.27 1.27)) hide)
    )
    (property "Author" "Antmicro" (at 365.76 253.365 0)
      (effects (font (size 1.27 1.27) (thickness 0.15)) (justify left bottom) hide)
    )
    (property "License" "Apache-2.0" (at 365.76 255.905 0)
      (effects (font (size 1.27 1.27) (thickness 0.15)) (justify left bottom) hide)
    )
    (pin "1")
    (instances
      (project "data-center-rdimm-ddr4-tester"
        (path ""
          (reference "#PWR0209") (unit 1)
        )
      )
    )
  )

  (symbol (lib_id "antmicroTestPoints:TP_1mm_SMD") (at 279.4 88.9 0) (unit 1)
    (in_bom yes) (on_board yes) (dnp no) (fields_autoplaced)
    (property "Reference" "1V0" (at 284.48 88.8999 0)
      (effects (font (size 1.27 1.27)) (justify left))
    )
    (property "Value" "TP_1mm_SMD" (at 294.64 96.52 0)
      (effects (font (size 1.27 1.27) (thickness 0.15)) (justify left bottom) hide)
    )
    (property "Footprint" "antmicro-footprints:TP_SMD_1mm" (at 294.64 99.06 0)
      (effects (font (size 1.27 1.27) (thickness 0.15)) (justify left bottom) hide)
    )
    (property "Datasheet" "" (at 294.64 101.6 0)
      (effects (font (size 1.27 1.27) (thickness 0.15)) (justify left bottom) hide)
    )
    (property "MPN" "" (at 279.4 88.9 0)
      (effects (font (size 1.27 1.27)) hide)
    )
    (property "Manufacturer" "" (at 279.4 88.9 0)
      (effects (font (size 1.27 1.27)) hide)
    )
    (property "Author" "Antmicro" (at 294.64 104.14 0)
      (effects (font (size 1.27 1.27) (thickness 0.15)) (justify left bottom) hide)
    )
    (property "License" "Apache-2.0" (at 294.64 106.68 0)
      (effects (font (size 1.27 1.27) (thickness 0.15)) (justify left bottom) hide)
    )
    (pin "1")
    (instances
      (project "data-center-rdimm-ddr4-tester"
        (path ""
          (reference "1V0") (unit 1)
        )
      )
    )
  )

  (symbol (lib_id "antmicroTestPoints:TP_1mm_SMD") (at 279.4 93.98 0) (unit 1)
    (in_bom yes) (on_board yes) (dnp no) (fields_autoplaced)
    (property "Reference" "1V8" (at 284.48 93.9799 0)
      (effects (font (size 1.27 1.27)) (justify left))
    )
    (property "Value" "TP_1mm_SMD" (at 294.64 101.6 0)
      (effects (font (size 1.27 1.27) (thickness 0.15)) (justify left bottom) hide)
    )
    (property "Footprint" "antmicro-footprints:TP_SMD_1mm" (at 294.64 104.14 0)
      (effects (font (size 1.27 1.27) (thickness 0.15)) (justify left bottom) hide)
    )
    (property "Datasheet" "" (at 294.64 106.68 0)
      (effects (font (size 1.27 1.27) (thickness 0.15)) (justify left bottom) hide)
    )
    (property "MPN" "" (at 279.4 93.98 0)
      (effects (font (size 1.27 1.27)) hide)
    )
    (property "Manufacturer" "" (at 279.4 93.98 0)
      (effects (font (size 1.27 1.27)) hide)
    )
    (property "Author" "Antmicro" (at 294.64 109.22 0)
      (effects (font (size 1.27 1.27) (thickness 0.15)) (justify left bottom) hide)
    )
    (property "License" "Apache-2.0" (at 294.64 111.76 0)
      (effects (font (size 1.27 1.27) (thickness 0.15)) (justify left bottom) hide)
    )
    (pin "1")
    (instances
      (project "data-center-rdimm-ddr4-tester"
        (path ""
          (reference "1V8") (unit 1)
        )
      )
    )
  )

  (symbol (lib_id "antmicroGenericPinHeaders:PinHeader_1x3_P2.54mm_Drill1.1mm") (at 382.27 235.585 0) (mirror y) (unit 1)
    (in_bom yes) (on_board yes) (dnp no) (fields_autoplaced)
    (property "Reference" "J8" (at 378.46 229.235 0)
      (effects (font (size 1.27 1.27)))
    )
    (property "Value" "PinHeader_1x3_P2.54mm_Drill1.1mm" (at 378.46 231.14 0)
      (effects (font (size 1.27 1.27) (thickness 0.15)) hide)
    )
    (property "Footprint" "antmicro-footprints:PinHeader_1x3_P2.54mm_Drill1.1mm" (at 361.95 245.745 0)
      (effects (font (size 1.27 1.27) (thickness 0.15)) (justify left bottom) hide)
    )
    (property "Datasheet" "https://katalog.we-online.de/em/datasheet/6130xx11121.pdf" (at 361.95 248.285 0)
      (effects (font (size 1.27 1.27) (thickness 0.15)) (justify left bottom) hide)
    )
    (property "MPN" "61300311121" (at 378.46 231.775 0)
      (effects (font (size 1.27 1.27) (thickness 0.15)))
    )
    (property "Manufacturer" "Würth Elektronik" (at 361.95 253.365 0)
      (effects (font (size 1.27 1.27) (thickness 0.15)) (justify left bottom) hide)
    )
    (property "Author" "Antmicro" (at 361.95 255.905 0)
      (effects (font (size 1.27 1.27) (thickness 0.15)) (justify left bottom) hide)
    )
    (property "License" "Apache-2.0" (at 361.95 258.445 0)
      (effects (font (size 1.27 1.27) (thickness 0.15)) (justify left bottom) hide)
    )
    (pin "1")
    (pin "2")
    (pin "3")
    (instances
      (project "data-center-rdimm-ddr4-tester"
        (path ""
          (reference "J8") (unit 1)
        )
      )
    )
  )

  (symbol (lib_id "antmicropower:GND") (at 207.01 134.62 0) (unit 1)
    (in_bom yes) (on_board yes) (dnp no) (fields_autoplaced)
    (property "Reference" "#PWR0300" (at 207.01 140.97 0)
      (effects (font (size 1.27 1.27)) hide)
    )
    (property "Value" "GND" (at 207.01 139.7 0)
      (effects (font (size 1.27 1.27)))
    )
    (property "Footprint" "" (at 207.01 134.62 0)
      (effects (font (size 1.27 1.27)) hide)
    )
    (property "Datasheet" "" (at 207.01 134.62 0)
      (effects (font (size 1.27 1.27)) hide)
    )
    (property "Author" "Antmicro" (at 215.9 142.24 0)
      (effects (font (size 1.27 1.27) (thickness 0.15)) (justify left bottom) hide)
    )
    (property "License" "Apache-2.0" (at 215.9 144.78 0)
      (effects (font (size 1.27 1.27) (thickness 0.15)) (justify left bottom) hide)
    )
    (pin "1")
    (instances
      (project "data-center-rdimm-ddr4-tester"
        (path ""
          (reference "#PWR0300") (unit 1)
        )
      )
    )
  )

  (symbol (lib_id "antmicropower:GND") (at 216.535 134.62 0) (unit 1)
    (in_bom yes) (on_board yes) (dnp no) (fields_autoplaced)
    (property "Reference" "#PWR0301" (at 216.535 140.97 0)
      (effects (font (size 1.27 1.27)) hide)
    )
    (property "Value" "GND" (at 216.535 139.7 0)
      (effects (font (size 1.27 1.27)))
    )
    (property "Footprint" "" (at 216.535 134.62 0)
      (effects (font (size 1.27 1.27)) hide)
    )
    (property "Datasheet" "" (at 216.535 134.62 0)
      (effects (font (size 1.27 1.27)) hide)
    )
    (property "Author" "Antmicro" (at 225.425 142.24 0)
      (effects (font (size 1.27 1.27) (thickness 0.15)) (justify left bottom) hide)
    )
    (property "License" "Apache-2.0" (at 225.425 144.78 0)
      (effects (font (size 1.27 1.27) (thickness 0.15)) (justify left bottom) hide)
    )
    (pin "1")
    (instances
      (project "data-center-rdimm-ddr4-tester"
        (path ""
          (reference "#PWR0301") (unit 1)
        )
      )
    )
  )

  (symbol (lib_id "antmicropower:GND") (at 266.7 131.445 0) (unit 1)
    (in_bom yes) (on_board yes) (dnp no) (fields_autoplaced)
    (property "Reference" "#PWR0302" (at 266.7 137.795 0)
      (effects (font (size 1.27 1.27)) hide)
    )
    (property "Value" "GND" (at 266.7 136.525 0)
      (effects (font (size 1.27 1.27)))
    )
    (property "Footprint" "" (at 266.7 131.445 0)
      (effects (font (size 1.27 1.27)) hide)
    )
    (property "Datasheet" "" (at 266.7 131.445 0)
      (effects (font (size 1.27 1.27)) hide)
    )
    (property "Author" "Antmicro" (at 275.59 139.065 0)
      (effects (font (size 1.27 1.27) (thickness 0.15)) (justify left bottom) hide)
    )
    (property "License" "Apache-2.0" (at 275.59 141.605 0)
      (effects (font (size 1.27 1.27) (thickness 0.15)) (justify left bottom) hide)
    )
    (pin "1")
    (instances
      (project "data-center-rdimm-ddr4-tester"
        (path ""
          (reference "#PWR0302") (unit 1)
        )
      )
    )
  )

  (symbol (lib_id "antmicropower:GND") (at 274.32 131.445 0) (unit 1)
    (in_bom yes) (on_board yes) (dnp no) (fields_autoplaced)
    (property "Reference" "#PWR0303" (at 274.32 137.795 0)
      (effects (font (size 1.27 1.27)) hide)
    )
    (property "Value" "GND" (at 274.32 136.525 0)
      (effects (font (size 1.27 1.27)))
    )
    (property "Footprint" "" (at 274.32 131.445 0)
      (effects (font (size 1.27 1.27)) hide)
    )
    (property "Datasheet" "" (at 274.32 131.445 0)
      (effects (font (size 1.27 1.27)) hide)
    )
    (property "Author" "Antmicro" (at 283.21 139.065 0)
      (effects (font (size 1.27 1.27) (thickness 0.15)) (justify left bottom) hide)
    )
    (property "License" "Apache-2.0" (at 283.21 141.605 0)
      (effects (font (size 1.27 1.27) (thickness 0.15)) (justify left bottom) hide)
    )
    (pin "1")
    (instances
      (project "data-center-rdimm-ddr4-tester"
        (path ""
          (reference "#PWR0303") (unit 1)
        )
      )
    )
  )

  (symbol (lib_id "antmicropower:GND") (at 281.94 131.445 0) (unit 1)
    (in_bom yes) (on_board yes) (dnp no) (fields_autoplaced)
    (property "Reference" "#PWR0304" (at 281.94 137.795 0)
      (effects (font (size 1.27 1.27)) hide)
    )
    (property "Value" "GND" (at 281.94 136.525 0)
      (effects (font (size 1.27 1.27)))
    )
    (property "Footprint" "" (at 281.94 131.445 0)
      (effects (font (size 1.27 1.27)) hide)
    )
    (property "Datasheet" "" (at 281.94 131.445 0)
      (effects (font (size 1.27 1.27)) hide)
    )
    (property "Author" "Antmicro" (at 290.83 139.065 0)
      (effects (font (size 1.27 1.27) (thickness 0.15)) (justify left bottom) hide)
    )
    (property "License" "Apache-2.0" (at 290.83 141.605 0)
      (effects (font (size 1.27 1.27) (thickness 0.15)) (justify left bottom) hide)
    )
    (pin "1")
    (instances
      (project "data-center-rdimm-ddr4-tester"
        (path ""
          (reference "#PWR0304") (unit 1)
        )
      )
    )
  )

  (symbol (lib_id "antmicroResistors0402:R_10k_0402") (at 255.905 132.08 270) (unit 1)
    (in_bom yes) (on_board yes) (dnp no) (fields_autoplaced)
    (property "Reference" "R82" (at 258.445 133.35 90)
      (effects (font (size 1.524 1.524)) (justify left))
    )
    (property "Value" "R_10k_0402" (at 243.205 152.4 0)
      (effects (font (size 1.27 1.27) (thickness 0.15)) (justify left bottom) hide)
    )
    (property "Footprint" "antmicro-footprints:R_0402_1005Metric" (at 240.665 152.4 0)
      (effects (font (size 1.27 1.27) (thickness 0.15)) (justify left bottom) hide)
    )
    (property "Datasheet" "https://www.bourns.com/docs/product-datasheets/cr.pdf" (at 238.125 152.4 0)
      (effects (font (size 1.27 1.27) (thickness 0.15)) (justify left bottom) hide)
    )
    (property "Manufacturer" "Bourns" (at 233.045 152.4 0)
      (effects (font (size 1.27 1.27) (thickness 0.15)) (justify left bottom) hide)
    )
    (property "MPN" "CR0402-FX-1002GLF" (at 235.585 152.4 0)
      (effects (font (size 1.27 1.27) (thickness 0.15)) (justify left bottom) hide)
    )
    (property "Val" "10k" (at 258.445 136.5249 90)
      (effects (font (size 1.27 1.27) (thickness 0.15)) (justify left))
    )
    (property "License" "Apache-2.0" (at 230.505 152.4 0)
      (effects (font (size 1.27 1.27) (thickness 0.15)) (justify left bottom) hide)
    )
    (property "Author" "Antmicro" (at 227.965 152.4 0)
      (effects (font (size 1.27 1.27) (thickness 0.15)) (justify left bottom) hide)
    )
    (property "Tolerance" "1%" (at 245.745 152.4 0)
      (effects (font (size 1.27 1.27)) (justify left bottom) hide)
    )
    (pin "1")
    (pin "2")
    (instances
      (project "data-center-rdimm-ddr4-tester"
        (path ""
          (reference "R82") (unit 1)
        )
      )
    )
  )

  (symbol (lib_id "antmicropower:GND") (at 255.905 137.16 0) (unit 1)
    (in_bom yes) (on_board yes) (dnp no) (fields_autoplaced)
    (property "Reference" "#PWR0305" (at 255.905 143.51 0)
      (effects (font (size 1.27 1.27)) hide)
    )
    (property "Value" "GND" (at 255.905 142.24 0)
      (effects (font (size 1.27 1.27)))
    )
    (property "Footprint" "" (at 255.905 137.16 0)
      (effects (font (size 1.27 1.27)) hide)
    )
    (property "Datasheet" "" (at 255.905 137.16 0)
      (effects (font (size 1.27 1.27)) hide)
    )
    (property "Author" "Antmicro" (at 264.795 144.78 0)
      (effects (font (size 1.27 1.27) (thickness 0.15)) (justify left bottom) hide)
    )
    (property "License" "Apache-2.0" (at 264.795 147.32 0)
      (effects (font (size 1.27 1.27) (thickness 0.15)) (justify left bottom) hide)
    )
    (pin "1")
    (instances
      (project "data-center-rdimm-ddr4-tester"
        (path ""
          (reference "#PWR0305") (unit 1)
        )
      )
    )
  )

  (symbol (lib_id "antmicroResistors0402:R_10k_0402") (at 259.715 171.45 270) (unit 1)
    (in_bom yes) (on_board yes) (dnp no) (fields_autoplaced)
    (property "Reference" "R84" (at 262.255 172.72 90)
      (effects (font (size 1.524 1.524)) (justify left))
    )
    (property "Value" "R_10k_0402" (at 247.015 191.77 0)
      (effects (font (size 1.27 1.27) (thickness 0.15)) (justify left bottom) hide)
    )
    (property "Footprint" "antmicro-footprints:R_0402_1005Metric" (at 244.475 191.77 0)
      (effects (font (size 1.27 1.27) (thickness 0.15)) (justify left bottom) hide)
    )
    (property "Datasheet" "https://www.bourns.com/docs/product-datasheets/cr.pdf" (at 241.935 191.77 0)
      (effects (font (size 1.27 1.27) (thickness 0.15)) (justify left bottom) hide)
    )
    (property "Manufacturer" "Bourns" (at 236.855 191.77 0)
      (effects (font (size 1.27 1.27) (thickness 0.15)) (justify left bottom) hide)
    )
    (property "MPN" "CR0402-FX-1002GLF" (at 239.395 191.77 0)
      (effects (font (size 1.27 1.27) (thickness 0.15)) (justify left bottom) hide)
    )
    (property "Val" "10k" (at 262.255 175.8949 90)
      (effects (font (size 1.27 1.27) (thickness 0.15)) (justify left))
    )
    (property "License" "Apache-2.0" (at 234.315 191.77 0)
      (effects (font (size 1.27 1.27) (thickness 0.15)) (justify left bottom) hide)
    )
    (property "Author" "Antmicro" (at 231.775 191.77 0)
      (effects (font (size 1.27 1.27) (thickness 0.15)) (justify left bottom) hide)
    )
    (property "Tolerance" "1%" (at 249.555 191.77 0)
      (effects (font (size 1.27 1.27)) (justify left bottom) hide)
    )
    (pin "1")
    (pin "2")
    (instances
      (project "data-center-rdimm-ddr4-tester"
        (path ""
          (reference "R84") (unit 1)
        )
      )
    )
  )

  (symbol (lib_id "antmicropower:GND") (at 259.715 176.53 0) (unit 1)
    (in_bom yes) (on_board yes) (dnp no) (fields_autoplaced)
    (property "Reference" "#PWR0311" (at 259.715 182.88 0)
      (effects (font (size 1.27 1.27)) hide)
    )
    (property "Value" "GND" (at 259.715 181.61 0)
      (effects (font (size 1.27 1.27)))
    )
    (property "Footprint" "" (at 259.715 176.53 0)
      (effects (font (size 1.27 1.27)) hide)
    )
    (property "Datasheet" "" (at 259.715 176.53 0)
      (effects (font (size 1.27 1.27)) hide)
    )
    (property "Author" "Antmicro" (at 268.605 184.15 0)
      (effects (font (size 1.27 1.27) (thickness 0.15)) (justify left bottom) hide)
    )
    (property "License" "Apache-2.0" (at 268.605 186.69 0)
      (effects (font (size 1.27 1.27) (thickness 0.15)) (justify left bottom) hide)
    )
    (pin "1")
    (instances
      (project "data-center-rdimm-ddr4-tester"
        (path ""
          (reference "#PWR0311") (unit 1)
        )
      )
    )
  )

  (symbol (lib_id "antmicroResistors0402:R_10k_0402") (at 259.08 210.185 270) (unit 1)
    (in_bom yes) (on_board yes) (dnp no) (fields_autoplaced)
    (property "Reference" "R46" (at 260.985 211.455 90)
      (effects (font (size 1.524 1.524)) (justify left))
    )
    (property "Value" "R_10k_0402" (at 246.38 230.505 0)
      (effects (font (size 1.27 1.27) (thickness 0.15)) (justify left bottom) hide)
    )
    (property "Footprint" "antmicro-footprints:R_0402_1005Metric" (at 243.84 230.505 0)
      (effects (font (size 1.27 1.27) (thickness 0.15)) (justify left bottom) hide)
    )
    (property "Datasheet" "https://www.bourns.com/docs/product-datasheets/cr.pdf" (at 241.3 230.505 0)
      (effects (font (size 1.27 1.27) (thickness 0.15)) (justify left bottom) hide)
    )
    (property "Manufacturer" "Bourns" (at 236.22 230.505 0)
      (effects (font (size 1.27 1.27) (thickness 0.15)) (justify left bottom) hide)
    )
    (property "MPN" "CR0402-FX-1002GLF" (at 238.76 230.505 0)
      (effects (font (size 1.27 1.27) (thickness 0.15)) (justify left bottom) hide)
    )
    (property "Val" "10k" (at 260.985 214.6299 90)
      (effects (font (size 1.27 1.27) (thickness 0.15)) (justify left))
    )
    (property "License" "Apache-2.0" (at 233.68 230.505 0)
      (effects (font (size 1.27 1.27) (thickness 0.15)) (justify left bottom) hide)
    )
    (property "Author" "Antmicro" (at 231.14 230.505 0)
      (effects (font (size 1.27 1.27) (thickness 0.15)) (justify left bottom) hide)
    )
    (property "Tolerance" "1%" (at 248.92 230.505 0)
      (effects (font (size 1.27 1.27)) (justify left bottom) hide)
    )
    (pin "1")
    (pin "2")
    (instances
      (project "data-center-rdimm-ddr4-tester"
        (path ""
          (reference "R46") (unit 1)
        )
      )
    )
  )

  (symbol (lib_id "antmicropower:GND") (at 259.08 215.265 0) (unit 1)
    (in_bom yes) (on_board yes) (dnp no) (fields_autoplaced)
    (property "Reference" "#PWR0299" (at 259.08 221.615 0)
      (effects (font (size 1.27 1.27)) hide)
    )
    (property "Value" "GND" (at 259.08 219.71 0)
      (effects (font (size 1.27 1.27)))
    )
    (property "Footprint" "" (at 259.08 215.265 0)
      (effects (font (size 1.27 1.27)) hide)
    )
    (property "Datasheet" "" (at 259.08 215.265 0)
      (effects (font (size 1.27 1.27)) hide)
    )
    (property "Author" "Antmicro" (at 267.97 222.885 0)
      (effects (font (size 1.27 1.27) (thickness 0.15)) (justify left bottom) hide)
    )
    (property "License" "Apache-2.0" (at 267.97 225.425 0)
      (effects (font (size 1.27 1.27) (thickness 0.15)) (justify left bottom) hide)
    )
    (pin "1")
    (instances
      (project "data-center-rdimm-ddr4-tester"
        (path ""
          (reference "#PWR0299") (unit 1)
        )
      )
    )
  )

  (symbol (lib_id "antmicroResistors0402:R_10k_0402") (at 254 261.62 270) (unit 1)
    (in_bom yes) (on_board yes) (dnp no) (fields_autoplaced)
    (property "Reference" "R43" (at 256.54 262.89 90)
      (effects (font (size 1.524 1.524)) (justify left))
    )
    (property "Value" "R_10k_0402" (at 241.3 281.94 0)
      (effects (font (size 1.27 1.27) (thickness 0.15)) (justify left bottom) hide)
    )
    (property "Footprint" "antmicro-footprints:R_0402_1005Metric" (at 238.76 281.94 0)
      (effects (font (size 1.27 1.27) (thickness 0.15)) (justify left bottom) hide)
    )
    (property "Datasheet" "https://www.bourns.com/docs/product-datasheets/cr.pdf" (at 236.22 281.94 0)
      (effects (font (size 1.27 1.27) (thickness 0.15)) (justify left bottom) hide)
    )
    (property "Manufacturer" "Bourns" (at 231.14 281.94 0)
      (effects (font (size 1.27 1.27) (thickness 0.15)) (justify left bottom) hide)
    )
    (property "MPN" "CR0402-FX-1002GLF" (at 233.68 281.94 0)
      (effects (font (size 1.27 1.27) (thickness 0.15)) (justify left bottom) hide)
    )
    (property "Val" "10k" (at 256.54 266.0649 90)
      (effects (font (size 1.27 1.27) (thickness 0.15)) (justify left))
    )
    (property "License" "Apache-2.0" (at 228.6 281.94 0)
      (effects (font (size 1.27 1.27) (thickness 0.15)) (justify left bottom) hide)
    )
    (property "Author" "Antmicro" (at 226.06 281.94 0)
      (effects (font (size 1.27 1.27) (thickness 0.15)) (justify left bottom) hide)
    )
    (property "Tolerance" "1%" (at 243.84 281.94 0)
      (effects (font (size 1.27 1.27)) (justify left bottom) hide)
    )
    (pin "1")
    (pin "2")
    (instances
      (project "data-center-rdimm-ddr4-tester"
        (path ""
          (reference "R43") (unit 1)
        )
      )
    )
  )

  (symbol (lib_id "antmicropower:GND") (at 254 266.7 0) (unit 1)
    (in_bom yes) (on_board yes) (dnp no) (fields_autoplaced)
    (property "Reference" "#PWR0298" (at 254 273.05 0)
      (effects (font (size 1.27 1.27)) hide)
    )
    (property "Value" "GND" (at 254 271.145 0)
      (effects (font (size 1.27 1.27)))
    )
    (property "Footprint" "" (at 254 266.7 0)
      (effects (font (size 1.27 1.27)) hide)
    )
    (property "Datasheet" "" (at 254 266.7 0)
      (effects (font (size 1.27 1.27)) hide)
    )
    (property "Author" "Antmicro" (at 262.89 274.32 0)
      (effects (font (size 1.27 1.27) (thickness 0.15)) (justify left bottom) hide)
    )
    (property "License" "Apache-2.0" (at 262.89 276.86 0)
      (effects (font (size 1.27 1.27) (thickness 0.15)) (justify left bottom) hide)
    )
    (pin "1")
    (instances
      (project "data-center-rdimm-ddr4-tester"
        (path ""
          (reference "#PWR0298") (unit 1)
        )
      )
    )
  )

  (symbol (lib_id "antmicropower:GND") (at 271.145 171.45 0) (unit 1)
    (in_bom yes) (on_board yes) (dnp no) (fields_autoplaced)
    (property "Reference" "#PWR0310" (at 271.145 177.8 0)
      (effects (font (size 1.27 1.27)) hide)
    )
    (property "Value" "GND" (at 271.145 176.53 0)
      (effects (font (size 1.27 1.27)))
    )
    (property "Footprint" "" (at 271.145 171.45 0)
      (effects (font (size 1.27 1.27)) hide)
    )
    (property "Datasheet" "" (at 271.145 171.45 0)
      (effects (font (size 1.27 1.27)) hide)
    )
    (property "Author" "Antmicro" (at 280.035 179.07 0)
      (effects (font (size 1.27 1.27) (thickness 0.15)) (justify left bottom) hide)
    )
    (property "License" "Apache-2.0" (at 280.035 181.61 0)
      (effects (font (size 1.27 1.27) (thickness 0.15)) (justify left bottom) hide)
    )
    (pin "1")
    (instances
      (project "data-center-rdimm-ddr4-tester"
        (path ""
          (reference "#PWR0310") (unit 1)
        )
      )
    )
  )

  (symbol (lib_id "antmicropower:GND") (at 278.765 171.45 0) (unit 1)
    (in_bom yes) (on_board yes) (dnp no) (fields_autoplaced)
    (property "Reference" "#PWR0309" (at 278.765 177.8 0)
      (effects (font (size 1.27 1.27)) hide)
    )
    (property "Value" "GND" (at 278.765 176.53 0)
      (effects (font (size 1.27 1.27)))
    )
    (property "Footprint" "" (at 278.765 171.45 0)
      (effects (font (size 1.27 1.27)) hide)
    )
    (property "Datasheet" "" (at 278.765 171.45 0)
      (effects (font (size 1.27 1.27)) hide)
    )
    (property "Author" "Antmicro" (at 287.655 179.07 0)
      (effects (font (size 1.27 1.27) (thickness 0.15)) (justify left bottom) hide)
    )
    (property "License" "Apache-2.0" (at 287.655 181.61 0)
      (effects (font (size 1.27 1.27) (thickness 0.15)) (justify left bottom) hide)
    )
    (pin "1")
    (instances
      (project "data-center-rdimm-ddr4-tester"
        (path ""
          (reference "#PWR0309") (unit 1)
        )
      )
    )
  )

  (symbol (lib_id "antmicropower:GND") (at 286.385 171.45 0) (unit 1)
    (in_bom yes) (on_board yes) (dnp no) (fields_autoplaced)
    (property "Reference" "#PWR0308" (at 286.385 177.8 0)
      (effects (font (size 1.27 1.27)) hide)
    )
    (property "Value" "GND" (at 286.385 176.53 0)
      (effects (font (size 1.27 1.27)))
    )
    (property "Footprint" "" (at 286.385 171.45 0)
      (effects (font (size 1.27 1.27)) hide)
    )
    (property "Datasheet" "" (at 286.385 171.45 0)
      (effects (font (size 1.27 1.27)) hide)
    )
    (property "Author" "Antmicro" (at 295.275 179.07 0)
      (effects (font (size 1.27 1.27) (thickness 0.15)) (justify left bottom) hide)
    )
    (property "License" "Apache-2.0" (at 295.275 181.61 0)
      (effects (font (size 1.27 1.27) (thickness 0.15)) (justify left bottom) hide)
    )
    (pin "1")
    (instances
      (project "data-center-rdimm-ddr4-tester"
        (path ""
          (reference "#PWR0308") (unit 1)
        )
      )
    )
  )

  (symbol (lib_id "antmicropower:GND") (at 268.605 209.55 0) (unit 1)
    (in_bom yes) (on_board yes) (dnp no) (fields_autoplaced)
    (property "Reference" "#PWR0297" (at 268.605 215.9 0)
      (effects (font (size 1.27 1.27)) hide)
    )
    (property "Value" "GND" (at 268.605 213.995 0)
      (effects (font (size 1.27 1.27)))
    )
    (property "Footprint" "" (at 268.605 209.55 0)
      (effects (font (size 1.27 1.27)) hide)
    )
    (property "Datasheet" "" (at 268.605 209.55 0)
      (effects (font (size 1.27 1.27)) hide)
    )
    (property "Author" "Antmicro" (at 277.495 217.17 0)
      (effects (font (size 1.27 1.27) (thickness 0.15)) (justify left bottom) hide)
    )
    (property "License" "Apache-2.0" (at 277.495 219.71 0)
      (effects (font (size 1.27 1.27) (thickness 0.15)) (justify left bottom) hide)
    )
    (pin "1")
    (instances
      (project "data-center-rdimm-ddr4-tester"
        (path ""
          (reference "#PWR0297") (unit 1)
        )
      )
    )
  )

  (symbol (lib_id "antmicropower:GND") (at 276.225 209.55 0) (unit 1)
    (in_bom yes) (on_board yes) (dnp no) (fields_autoplaced)
    (property "Reference" "#PWR0296" (at 276.225 215.9 0)
      (effects (font (size 1.27 1.27)) hide)
    )
    (property "Value" "GND" (at 276.225 213.995 0)
      (effects (font (size 1.27 1.27)))
    )
    (property "Footprint" "" (at 276.225 209.55 0)
      (effects (font (size 1.27 1.27)) hide)
    )
    (property "Datasheet" "" (at 276.225 209.55 0)
      (effects (font (size 1.27 1.27)) hide)
    )
    (property "Author" "Antmicro" (at 285.115 217.17 0)
      (effects (font (size 1.27 1.27) (thickness 0.15)) (justify left bottom) hide)
    )
    (property "License" "Apache-2.0" (at 285.115 219.71 0)
      (effects (font (size 1.27 1.27) (thickness 0.15)) (justify left bottom) hide)
    )
    (pin "1")
    (instances
      (project "data-center-rdimm-ddr4-tester"
        (path ""
          (reference "#PWR0296") (unit 1)
        )
      )
    )
  )

  (symbol (lib_id "antmicropower:GND") (at 283.845 209.55 0) (unit 1)
    (in_bom yes) (on_board yes) (dnp no) (fields_autoplaced)
    (property "Reference" "#PWR0295" (at 283.845 215.9 0)
      (effects (font (size 1.27 1.27)) hide)
    )
    (property "Value" "GND" (at 283.845 213.995 0)
      (effects (font (size 1.27 1.27)))
    )
    (property "Footprint" "" (at 283.845 209.55 0)
      (effects (font (size 1.27 1.27)) hide)
    )
    (property "Datasheet" "" (at 283.845 209.55 0)
      (effects (font (size 1.27 1.27)) hide)
    )
    (property "Author" "Antmicro" (at 292.735 217.17 0)
      (effects (font (size 1.27 1.27) (thickness 0.15)) (justify left bottom) hide)
    )
    (property "License" "Apache-2.0" (at 292.735 219.71 0)
      (effects (font (size 1.27 1.27) (thickness 0.15)) (justify left bottom) hide)
    )
    (pin "1")
    (instances
      (project "data-center-rdimm-ddr4-tester"
        (path ""
          (reference "#PWR0295") (unit 1)
        )
      )
    )
  )

  (symbol (lib_id "antmicropower:GND") (at 265.43 257.175 0) (unit 1)
    (in_bom yes) (on_board yes) (dnp no) (fields_autoplaced)
    (property "Reference" "#PWR0294" (at 265.43 263.525 0)
      (effects (font (size 1.27 1.27)) hide)
    )
    (property "Value" "GND" (at 265.43 262.255 0)
      (effects (font (size 1.27 1.27)))
    )
    (property "Footprint" "" (at 265.43 257.175 0)
      (effects (font (size 1.27 1.27)) hide)
    )
    (property "Datasheet" "" (at 265.43 257.175 0)
      (effects (font (size 1.27 1.27)) hide)
    )
    (property "Author" "Antmicro" (at 274.32 264.795 0)
      (effects (font (size 1.27 1.27) (thickness 0.15)) (justify left bottom) hide)
    )
    (property "License" "Apache-2.0" (at 274.32 267.335 0)
      (effects (font (size 1.27 1.27) (thickness 0.15)) (justify left bottom) hide)
    )
    (pin "1")
    (instances
      (project "data-center-rdimm-ddr4-tester"
        (path ""
          (reference "#PWR0294") (unit 1)
        )
      )
    )
  )

  (symbol (lib_id "antmicropower:GND") (at 272.415 257.175 0) (unit 1)
    (in_bom yes) (on_board yes) (dnp no) (fields_autoplaced)
    (property "Reference" "#PWR0180" (at 272.415 263.525 0)
      (effects (font (size 1.27 1.27)) hide)
    )
    (property "Value" "GND" (at 272.415 262.255 0)
      (effects (font (size 1.27 1.27)))
    )
    (property "Footprint" "" (at 272.415 257.175 0)
      (effects (font (size 1.27 1.27)) hide)
    )
    (property "Datasheet" "" (at 272.415 257.175 0)
      (effects (font (size 1.27 1.27)) hide)
    )
    (property "Author" "Antmicro" (at 281.305 264.795 0)
      (effects (font (size 1.27 1.27) (thickness 0.15)) (justify left bottom) hide)
    )
    (property "License" "Apache-2.0" (at 281.305 267.335 0)
      (effects (font (size 1.27 1.27) (thickness 0.15)) (justify left bottom) hide)
    )
    (pin "1")
    (instances
      (project "data-center-rdimm-ddr4-tester"
        (path ""
          (reference "#PWR0180") (unit 1)
        )
      )
    )
  )

  (symbol (lib_id "antmicropower:GND") (at 279.4 257.175 0) (unit 1)
    (in_bom yes) (on_board yes) (dnp no) (fields_autoplaced)
    (property "Reference" "#PWR0179" (at 279.4 263.525 0)
      (effects (font (size 1.27 1.27)) hide)
    )
    (property "Value" "GND" (at 279.4 262.255 0)
      (effects (font (size 1.27 1.27)))
    )
    (property "Footprint" "" (at 279.4 257.175 0)
      (effects (font (size 1.27 1.27)) hide)
    )
    (property "Datasheet" "" (at 279.4 257.175 0)
      (effects (font (size 1.27 1.27)) hide)
    )
    (property "Author" "Antmicro" (at 288.29 264.795 0)
      (effects (font (size 1.27 1.27) (thickness 0.15)) (justify left bottom) hide)
    )
    (property "License" "Apache-2.0" (at 288.29 267.335 0)
      (effects (font (size 1.27 1.27) (thickness 0.15)) (justify left bottom) hide)
    )
    (pin "1")
    (instances
      (project "data-center-rdimm-ddr4-tester"
        (path ""
          (reference "#PWR0179") (unit 1)
        )
      )
    )
  )

  (symbol (lib_id "antmicroCapacitors0402:C_1u_0402") (at 281.94 126.365 270) (unit 1)
    (in_bom yes) (on_board yes) (dnp no)
    (property "Reference" "C220" (at 282.575 127 90)
      (effects (font (size 1.524 1.524)) (justify left))
    )
    (property "Value" "C_1u_0402" (at 271.78 146.685 0)
      (effects (font (size 1.27 1.27) (thickness 0.15)) (justify left bottom) hide)
    )
    (property "Footprint" "antmicro-footprints:C_0402_1005Metric" (at 269.24 146.685 0)
      (effects (font (size 1.27 1.27) (thickness 0.15)) (justify left bottom) hide)
    )
    (property "Datasheet" " " (at 266.7 146.685 0)
      (effects (font (size 1.27 1.27) (thickness 0.15)) (justify left bottom) hide)
    )
    (property "Manufacturer" "TDK" (at 261.62 146.685 0)
      (effects (font (size 1.27 1.27) (thickness 0.15)) (justify left bottom) hide)
    )
    (property "MPN" "C1005X6S1A105K050BC" (at 264.16 146.685 0)
      (effects (font (size 1.27 1.27) (thickness 0.15)) (justify left bottom) hide)
    )
    (property "Val" "1u" (at 282.575 130.81 90)
      (effects (font (size 1.27 1.27) (thickness 0.15)) (justify left))
    )
    (property "License" "Apache-2.0" (at 259.08 146.685 0)
      (effects (font (size 1.27 1.27) (thickness 0.15)) (justify left bottom) hide)
    )
    (property "Author" "Antmicro" (at 256.54 146.685 0)
      (effects (font (size 1.27 1.27) (thickness 0.15)) (justify left bottom) hide)
    )
    (property "Voltage" "" (at 254 146.685 0)
      (effects (font (size 1.27 1.27)) (justify left bottom) hide)
    )
    (property "Dielectric" "" (at 251.46 146.685 0)
      (effects (font (size 1.27 1.27)) (justify left bottom) hide)
    )
    (pin "1")
    (pin "2")
    (instances
      (project "data-center-rdimm-ddr4-tester"
        (path ""
          (reference "C220") (unit 1)
        )
      )
    )
  )

  (symbol (lib_id "antmicroCapacitors0402:C_22u_0402") (at 274.32 126.365 270) (unit 1)
    (in_bom yes) (on_board yes) (dnp no)
    (property "Reference" "C218" (at 274.955 127 90)
      (effects (font (size 1.524 1.524)) (justify left))
    )
    (property "Value" "C_22u_0402" (at 264.16 146.685 0)
      (effects (font (size 1.27 1.27) (thickness 0.15)) (justify left bottom) hide)
    )
    (property "Footprint" "antmicro-footprints:C_0402_1005Metric" (at 261.62 146.685 0)
      (effects (font (size 1.27 1.27) (thickness 0.15)) (justify left bottom) hide)
    )
    (property "Datasheet" " " (at 259.08 146.685 0)
      (effects (font (size 1.27 1.27) (thickness 0.15)) (justify left bottom) hide)
    )
    (property "Manufacturer" "AVX" (at 254 146.685 0)
      (effects (font (size 1.27 1.27) (thickness 0.15)) (justify left bottom) hide)
    )
    (property "MPN" "04024W226MAT2A" (at 256.54 146.685 0)
      (effects (font (size 1.27 1.27) (thickness 0.15)) (justify left bottom) hide)
    )
    (property "Val" "22u" (at 274.955 130.81 90)
      (effects (font (size 1.27 1.27) (thickness 0.15)) (justify left))
    )
    (property "License" "Apache-2.0" (at 251.46 146.685 0)
      (effects (font (size 1.27 1.27) (thickness 0.15)) (justify left bottom) hide)
    )
    (property "Author" "Antmicro" (at 248.92 146.685 0)
      (effects (font (size 1.27 1.27) (thickness 0.15)) (justify left bottom) hide)
    )
    (property "Voltage" "" (at 246.38 146.685 0)
      (effects (font (size 1.27 1.27)) (justify left bottom) hide)
    )
    (property "Dielectric" "" (at 243.84 146.685 0)
      (effects (font (size 1.27 1.27)) (justify left bottom) hide)
    )
    (pin "1")
    (pin "2")
    (instances
      (project "data-center-rdimm-ddr4-tester"
        (path ""
          (reference "C218") (unit 1)
        )
      )
    )
  )

  (symbol (lib_id "antmicroCapacitors0402:C_22u_0402") (at 266.7 126.365 270) (unit 1)
    (in_bom yes) (on_board yes) (dnp no)
    (property "Reference" "C216" (at 267.335 127 90)
      (effects (font (size 1.524 1.524)) (justify left))
    )
    (property "Value" "C_22u_0402" (at 256.54 146.685 0)
      (effects (font (size 1.27 1.27) (thickness 0.15)) (justify left bottom) hide)
    )
    (property "Footprint" "antmicro-footprints:C_0402_1005Metric" (at 254 146.685 0)
      (effects (font (size 1.27 1.27) (thickness 0.15)) (justify left bottom) hide)
    )
    (property "Datasheet" " " (at 251.46 146.685 0)
      (effects (font (size 1.27 1.27) (thickness 0.15)) (justify left bottom) hide)
    )
    (property "Manufacturer" "AVX" (at 246.38 146.685 0)
      (effects (font (size 1.27 1.27) (thickness 0.15)) (justify left bottom) hide)
    )
    (property "MPN" "04024W226MAT2A" (at 248.92 146.685 0)
      (effects (font (size 1.27 1.27) (thickness 0.15)) (justify left bottom) hide)
    )
    (property "Val" "22u" (at 267.335 130.81 90)
      (effects (font (size 1.27 1.27) (thickness 0.15)) (justify left))
    )
    (property "License" "Apache-2.0" (at 243.84 146.685 0)
      (effects (font (size 1.27 1.27) (thickness 0.15)) (justify left bottom) hide)
    )
    (property "Author" "Antmicro" (at 241.3 146.685 0)
      (effects (font (size 1.27 1.27) (thickness 0.15)) (justify left bottom) hide)
    )
    (property "Voltage" "" (at 238.76 146.685 0)
      (effects (font (size 1.27 1.27)) (justify left bottom) hide)
    )
    (property "Dielectric" "" (at 236.22 146.685 0)
      (effects (font (size 1.27 1.27)) (justify left bottom) hide)
    )
    (pin "1")
    (pin "2")
    (instances
      (project "data-center-rdimm-ddr4-tester"
        (path ""
          (reference "C216") (unit 1)
        )
      )
    )
  )

  (symbol (lib_id "antmicroCapacitors0402:C_100n_0402") (at 239.395 125.095 0) (unit 1)
    (in_bom yes) (on_board yes) (dnp no)
    (property "Reference" "C157" (at 241.935 122.555 0)
      (effects (font (size 1.27 1.27)))
    )
    (property "Value" "C_100n_0402" (at 259.715 135.255 0)
      (effects (font (size 1.27 1.27) (thickness 0.15)) (justify left bottom) hide)
    )
    (property "Footprint" "antmicro-footprints:C_0402_1005Metric" (at 259.715 137.795 0)
      (effects (font (size 1.27 1.27) (thickness 0.15)) (justify left bottom) hide)
    )
    (property "Datasheet" "https://search.murata.co.jp/Ceramy/image/img/A01X/G101/ENG/GRM155R61H104KE14-01.pdf" (at 259.715 140.335 0)
      (effects (font (size 1.27 1.27) (thickness 0.15)) (justify left bottom) hide)
    )
    (property "MPN" "GRM155R61H104KE14D" (at 259.715 142.875 0)
      (effects (font (size 1.27 1.27) (thickness 0.15)) (justify left bottom) hide)
    )
    (property "Manufacturer" "Murata" (at 259.715 145.415 0)
      (effects (font (size 1.27 1.27) (thickness 0.15)) (justify left bottom) hide)
    )
    (property "Val" "100n" (at 241.935 127.635 0)
      (effects (font (size 1.27 1.27) (thickness 0.15)))
    )
    (property "License" "Apache-2.0" (at 259.715 147.955 0)
      (effects (font (size 1.27 1.27) (thickness 0.15)) (justify left bottom) hide)
    )
    (property "Author" "Antmicro" (at 259.715 150.495 0)
      (effects (font (size 1.27 1.27) (thickness 0.15)) (justify left bottom) hide)
    )
    (property "Voltage" "50V" (at 259.715 153.035 0)
      (effects (font (size 1.27 1.27)) (justify left bottom) hide)
    )
    (property "Dielectric" "X5R" (at 259.715 155.575 0)
      (effects (font (size 1.27 1.27)) (justify left bottom) hide)
    )
    (pin "1")
    (pin "2")
    (instances
      (project "data-center-rdimm-ddr4-tester"
        (path ""
          (reference "C157") (unit 1)
        )
      )
    )
  )

  (symbol (lib_id "antmicroResistors0402:R_0R_0402") (at 210.82 125.095 0) (unit 1)
    (in_bom yes) (on_board yes) (dnp no)
    (property "Reference" "R47" (at 213.36 121.285 0)
      (effects (font (size 1.524 1.524)))
    )
    (property "Value" "R_0R_0402" (at 231.14 137.795 0)
      (effects (font (size 1.27 1.27) (thickness 0.15)) (justify left bottom) hide)
    )
    (property "Footprint" "antmicro-footprints:R_0402_1005Metric" (at 231.14 140.335 0)
      (effects (font (size 1.27 1.27) (thickness 0.15)) (justify left bottom) hide)
    )
    (property "Datasheet" "https://industrial.panasonic.com/cdbs/www-data/pdf/RDA0000/AOA0000C301.pdf" (at 231.14 142.875 0)
      (effects (font (size 1.27 1.27) (thickness 0.15)) (justify left bottom) hide)
    )
    (property "Manufacturer" "Panasonic" (at 231.14 147.955 0)
      (effects (font (size 1.27 1.27) (thickness 0.15)) (justify left bottom) hide)
    )
    (property "MPN" "ERJ2GE0R00X" (at 231.14 145.415 0)
      (effects (font (size 1.27 1.27) (thickness 0.15)) (justify left bottom) hide)
    )
    (property "Val" "0R" (at 213.36 123.19 0)
      (effects (font (size 1.27 1.27) (thickness 0.15)))
    )
    (property "License" "Apache-2.0" (at 231.14 150.495 0)
      (effects (font (size 1.27 1.27) (thickness 0.15)) (justify left bottom) hide)
    )
    (property "Author" "Antmicro" (at 231.14 153.035 0)
      (effects (font (size 1.27 1.27) (thickness 0.15)) (justify left bottom) hide)
    )
    (property "Tolerance" "~" (at 231.14 135.255 0)
      (effects (font (size 1.27 1.27)) (justify left bottom) hide)
    )
    (property "Current" "1A" (at 231.14 155.575 0)
      (effects (font (size 1.27 1.27) (thickness 0.15)) (justify left bottom) hide)
    )
    (pin "1")
    (pin "2")
    (instances
      (project "data-center-rdimm-ddr4-tester"
        (path ""
          (reference "R47") (unit 1)
        )
      )
    )
  )

  (symbol (lib_id "data-center-rdimm-ddr4-tester:AP62301WU-7") (at 222.25 170.18 0) (unit 1)
    (in_bom yes) (on_board yes) (dnp no) (fields_autoplaced)
    (property "Reference" "U12" (at 232.41 151.13 0)
      (effects (font (size 1.27 1.27)))
    )
    (property "Value" "AP62301WU-7" (at 232.41 153.67 0)
      (effects (font (size 1.27 1.27) (thickness 0.15)))
    )
    (property "Footprint" "data-center-rdimm-ddr4-tester-footprints:AP62301WU-7-TSOT23-6" (at 257.81 167.64 0)
      (effects (font (size 1.27 1.27) (thickness 0.15)) (justify left bottom) hide)
    )
    (property "Datasheet" "https://www.diodes.com/assets/Datasheets/AP62300_AP62301_AP62300T.pdf" (at 257.81 170.18 0)
      (effects (font (size 1.27 1.27) (thickness 0.15)) (justify left bottom) hide)
    )
    (property "MPN" "AP62301WU-7" (at 257.81 172.72 0)
      (effects (font (size 1.27 1.27) (thickness 0.15)) (justify left bottom) hide)
    )
    (property "Manufacturer" "Diodes Incorporated" (at 257.81 175.26 0)
      (effects (font (size 1.27 1.27) (thickness 0.15)) (justify left bottom) hide)
    )
    (property "Author" "Antmicro" (at 257.81 177.8 0)
      (effects (font (size 1.27 1.27) (thickness 0.15)) (justify left bottom) hide)
    )
    (property "License" "Apache-2.0" (at 257.81 180.34 0)
      (effects (font (size 1.27 1.27) (thickness 0.15)) (justify left bottom) hide)
    )
    (pin "1")
    (pin "2")
    (pin "3")
    (pin "4")
    (pin "5")
    (pin "6")
    (instances
      (project "data-center-rdimm-ddr4-tester"
        (path ""
          (reference "U12") (unit 1)
        )
      )
    )
  )

  (symbol (lib_id "antmicroCapacitors0402:C_10u_0402") (at 207.01 129.54 270) (unit 1)
    (in_bom yes) (on_board yes) (dnp no) (fields_autoplaced)
    (property "Reference" "C150" (at 209.55 130.8163 90)
      (effects (font (size 1.524 1.524)) (justify left))
    )
    (property "Value" "C_10u_0402" (at 196.85 149.86 0)
      (effects (font (size 1.27 1.27) (thickness 0.15)) (justify left bottom) hide)
    )
    (property "Footprint" "antmicro-footprints:C_0402_1005Metric" (at 194.31 149.86 0)
      (effects (font (size 1.27 1.27) (thickness 0.15)) (justify left bottom) hide)
    )
    (property "Datasheet" " " (at 191.77 149.86 0)
      (effects (font (size 1.27 1.27) (thickness 0.15)) (justify left bottom) hide)
    )
    (property "Manufacturer" "Yaego" (at 186.69 149.86 0)
      (effects (font (size 1.27 1.27) (thickness 0.15)) (justify left bottom) hide)
    )
    (property "MPN" "CC0402MRX5R5BB106" (at 189.23 149.86 0)
      (effects (font (size 1.27 1.27) (thickness 0.15)) (justify left bottom) hide)
    )
    (property "Val" "10u" (at 209.55 133.9912 90)
      (effects (font (size 1.27 1.27) (thickness 0.15)) (justify left))
    )
    (property "License" "Apache-2.0" (at 184.15 149.86 0)
      (effects (font (size 1.27 1.27) (thickness 0.15)) (justify left bottom) hide)
    )
    (property "Author" "Antmicro" (at 181.61 149.86 0)
      (effects (font (size 1.27 1.27) (thickness 0.15)) (justify left bottom) hide)
    )
    (property "Voltage" "" (at 179.07 149.86 0)
      (effects (font (size 1.27 1.27)) (justify left bottom) hide)
    )
    (property "Dielectric" "" (at 176.53 149.86 0)
      (effects (font (size 1.27 1.27)) (justify left bottom) hide)
    )
    (pin "1")
    (pin "2")
    (instances
      (project "data-center-rdimm-ddr4-tester"
        (path ""
          (reference "C150") (unit 1)
        )
      )
    )
  )

  (symbol (lib_id "data-center-rdimm-ddr4-tester:L_1u5_6A_1716") (at 252.095 160.02 0) (unit 1)
    (in_bom yes) (on_board yes) (dnp no) (fields_autoplaced)
    (property "Reference" "L7" (at 254.635 153.67 0)
      (effects (font (size 1.524 1.524)))
    )
    (property "Value" "L_1u5_6A_1716" (at 267.335 165.1 0)
      (effects (font (size 1.27 1.27) (thickness 0.15)) (justify left bottom) hide)
    )
    (property "Footprint" "data-center-rdimm-ddr4-tester-footprints:L_1716_4441Metric" (at 267.335 170.18 0)
      (effects (font (size 1.27 1.27) (thickness 0.15)) (justify left bottom) hide)
    )
    (property "Datasheet" "https://www.mouser.pl/datasheet/2/54/srp0420-1838509.pdf" (at 267.335 172.72 0)
      (effects (font (size 1.27 1.27) (thickness 0.15)) (justify left bottom) hide)
    )
    (property "Manufacturer" "Bourns" (at 267.335 177.8 0)
      (effects (font (size 1.27 1.27) (thickness 0.15)) (justify left bottom) hide)
    )
    (property "MPN" "SRP0420-1R5K" (at 267.335 175.26 0)
      (effects (font (size 1.27 1.27) (thickness 0.15)) (justify left bottom) hide)
    )
    (property "MaxCur" "6A" (at 267.335 180.34 0)
      (effects (font (size 1.27 1.27) (thickness 0.15)) (justify left bottom) hide)
    )
    (property "Size" "4.40x4.10" (at 267.335 182.88 0)
      (effects (font (size 1.27 1.27) (thickness 0.15)) (justify left bottom) hide)
    )
    (property "Val" "1u5/6A" (at 254.635 157.48 0)
      (effects (font (size 1.27 1.27) (thickness 0.15)))
    )
    (property "Author" "Antmicro" (at 267.335 185.42 0)
      (effects (font (size 1.27 1.27) (thickness 0.15)) (justify left bottom) hide)
    )
    (property "License" "Apache-2.0" (at 267.335 187.96 0)
      (effects (font (size 1.27 1.27) (thickness 0.15)) (justify left bottom) hide)
    )
    (pin "1")
    (pin "2")
    (instances
      (project "data-center-rdimm-ddr4-tester"
        (path ""
          (reference "L7") (unit 1)
        )
      )
    )
  )

  (symbol (lib_id "antmicroCapacitors0402:C_10u_0402") (at 210.185 167.64 270) (unit 1)
    (in_bom yes) (on_board yes) (dnp no) (fields_autoplaced)
    (property "Reference" "C151" (at 213.36 168.9163 90)
      (effects (font (size 1.524 1.524)) (justify left))
    )
    (property "Value" "C_10u_0402" (at 200.025 187.96 0)
      (effects (font (size 1.27 1.27) (thickness 0.15)) (justify left bottom) hide)
    )
    (property "Footprint" "antmicro-footprints:C_0402_1005Metric" (at 197.485 187.96 0)
      (effects (font (size 1.27 1.27) (thickness 0.15)) (justify left bottom) hide)
    )
    (property "Datasheet" " " (at 194.945 187.96 0)
      (effects (font (size 1.27 1.27) (thickness 0.15)) (justify left bottom) hide)
    )
    (property "Manufacturer" "Yaego" (at 189.865 187.96 0)
      (effects (font (size 1.27 1.27) (thickness 0.15)) (justify left bottom) hide)
    )
    (property "MPN" "CC0402MRX5R5BB106" (at 192.405 187.96 0)
      (effects (font (size 1.27 1.27) (thickness 0.15)) (justify left bottom) hide)
    )
    (property "Val" "10u" (at 213.36 172.0912 90)
      (effects (font (size 1.27 1.27) (thickness 0.15)) (justify left))
    )
    (property "License" "Apache-2.0" (at 187.325 187.96 0)
      (effects (font (size 1.27 1.27) (thickness 0.15)) (justify left bottom) hide)
    )
    (property "Author" "Antmicro" (at 184.785 187.96 0)
      (effects (font (size 1.27 1.27) (thickness 0.15)) (justify left bottom) hide)
    )
    (property "Voltage" "" (at 182.245 187.96 0)
      (effects (font (size 1.27 1.27)) (justify left bottom) hide)
    )
    (property "Dielectric" "" (at 179.705 187.96 0)
      (effects (font (size 1.27 1.27)) (justify left bottom) hide)
    )
    (pin "1")
    (pin "2")
    (instances
      (project "data-center-rdimm-ddr4-tester"
        (path ""
          (reference "C151") (unit 1)
        )
      )
    )
  )

  (symbol (lib_id "antmicroCapacitors0402:C_10u_0402") (at 208.915 205.74 270) (unit 1)
    (in_bom yes) (on_board yes) (dnp no) (fields_autoplaced)
    (property "Reference" "C99" (at 211.455 207.0163 90)
      (effects (font (size 1.524 1.524)) (justify left))
    )
    (property "Value" "C_10u_0402" (at 198.755 226.06 0)
      (effects (font (size 1.27 1.27) (thickness 0.15)) (justify left bottom) hide)
    )
    (property "Footprint" "antmicro-footprints:C_0402_1005Metric" (at 196.215 226.06 0)
      (effects (font (size 1.27 1.27) (thickness 0.15)) (justify left bottom) hide)
    )
    (property "Datasheet" " " (at 193.675 226.06 0)
      (effects (font (size 1.27 1.27) (thickness 0.15)) (justify left bottom) hide)
    )
    (property "Manufacturer" "Yaego" (at 188.595 226.06 0)
      (effects (font (size 1.27 1.27) (thickness 0.15)) (justify left bottom) hide)
    )
    (property "MPN" "CC0402MRX5R5BB106" (at 191.135 226.06 0)
      (effects (font (size 1.27 1.27) (thickness 0.15)) (justify left bottom) hide)
    )
    (property "Val" "10u" (at 211.455 210.1912 90)
      (effects (font (size 1.27 1.27) (thickness 0.15)) (justify left))
    )
    (property "License" "Apache-2.0" (at 186.055 226.06 0)
      (effects (font (size 1.27 1.27) (thickness 0.15)) (justify left bottom) hide)
    )
    (property "Author" "Antmicro" (at 183.515 226.06 0)
      (effects (font (size 1.27 1.27) (thickness 0.15)) (justify left bottom) hide)
    )
    (property "Voltage" "" (at 180.975 226.06 0)
      (effects (font (size 1.27 1.27)) (justify left bottom) hide)
    )
    (property "Dielectric" "" (at 178.435 226.06 0)
      (effects (font (size 1.27 1.27)) (justify left bottom) hide)
    )
    (pin "1")
    (pin "2")
    (instances
      (project "data-center-rdimm-ddr4-tester"
        (path ""
          (reference "C99") (unit 1)
        )
      )
    )
  )

  (symbol (lib_id "antmicroCapacitors0402:C_10u_0402") (at 205.74 255.905 270) (unit 1)
    (in_bom yes) (on_board yes) (dnp no) (fields_autoplaced)
    (property "Reference" "C45" (at 208.915 257.1813 90)
      (effects (font (size 1.524 1.524)) (justify left))
    )
    (property "Value" "C_10u_0402" (at 195.58 276.225 0)
      (effects (font (size 1.27 1.27) (thickness 0.15)) (justify left bottom) hide)
    )
    (property "Footprint" "antmicro-footprints:C_0402_1005Metric" (at 193.04 276.225 0)
      (effects (font (size 1.27 1.27) (thickness 0.15)) (justify left bottom) hide)
    )
    (property "Datasheet" " " (at 190.5 276.225 0)
      (effects (font (size 1.27 1.27) (thickness 0.15)) (justify left bottom) hide)
    )
    (property "Manufacturer" "Yaego" (at 185.42 276.225 0)
      (effects (font (size 1.27 1.27) (thickness 0.15)) (justify left bottom) hide)
    )
    (property "MPN" "CC0402MRX5R5BB106" (at 187.96 276.225 0)
      (effects (font (size 1.27 1.27) (thickness 0.15)) (justify left bottom) hide)
    )
    (property "Val" "10u" (at 208.915 260.3562 90)
      (effects (font (size 1.27 1.27) (thickness 0.15)) (justify left))
    )
    (property "License" "Apache-2.0" (at 182.88 276.225 0)
      (effects (font (size 1.27 1.27) (thickness 0.15)) (justify left bottom) hide)
    )
    (property "Author" "Antmicro" (at 180.34 276.225 0)
      (effects (font (size 1.27 1.27) (thickness 0.15)) (justify left bottom) hide)
    )
    (property "Voltage" "" (at 177.8 276.225 0)
      (effects (font (size 1.27 1.27)) (justify left bottom) hide)
    )
    (property "Dielectric" "" (at 175.26 276.225 0)
      (effects (font (size 1.27 1.27)) (justify left bottom) hide)
    )
    (pin "1")
    (pin "2")
    (instances
      (project "data-center-rdimm-ddr4-tester"
        (path ""
          (reference "C45") (unit 1)
        )
      )
    )
  )

  (symbol (lib_id "antmicroCapacitors0402:C_100n_0402") (at 243.205 165.1 0) (unit 1)
    (in_bom yes) (on_board yes) (dnp no)
    (property "Reference" "C158" (at 245.745 162.56 0)
      (effects (font (size 1.27 1.27)))
    )
    (property "Value" "C_100n_0402" (at 263.525 175.26 0)
      (effects (font (size 1.27 1.27) (thickness 0.15)) (justify left bottom) hide)
    )
    (property "Footprint" "antmicro-footprints:C_0402_1005Metric" (at 263.525 177.8 0)
      (effects (font (size 1.27 1.27) (thickness 0.15)) (justify left bottom) hide)
    )
    (property "Datasheet" "https://search.murata.co.jp/Ceramy/image/img/A01X/G101/ENG/GRM155R61H104KE14-01.pdf" (at 263.525 180.34 0)
      (effects (font (size 1.27 1.27) (thickness 0.15)) (justify left bottom) hide)
    )
    (property "MPN" "GRM155R61H104KE14D" (at 263.525 182.88 0)
      (effects (font (size 1.27 1.27) (thickness 0.15)) (justify left bottom) hide)
    )
    (property "Manufacturer" "Murata" (at 263.525 185.42 0)
      (effects (font (size 1.27 1.27) (thickness 0.15)) (justify left bottom) hide)
    )
    (property "Val" "100n" (at 245.745 167.64 0)
      (effects (font (size 1.27 1.27) (thickness 0.15)))
    )
    (property "License" "Apache-2.0" (at 263.525 187.96 0)
      (effects (font (size 1.27 1.27) (thickness 0.15)) (justify left bottom) hide)
    )
    (property "Author" "Antmicro" (at 263.525 190.5 0)
      (effects (font (size 1.27 1.27) (thickness 0.15)) (justify left bottom) hide)
    )
    (property "Voltage" "50V" (at 263.525 193.04 0)
      (effects (font (size 1.27 1.27)) (justify left bottom) hide)
    )
    (property "Dielectric" "X5R" (at 263.525 195.58 0)
      (effects (font (size 1.27 1.27)) (justify left bottom) hide)
    )
    (pin "1")
    (pin "2")
    (instances
      (project "data-center-rdimm-ddr4-tester"
        (path ""
          (reference "C158") (unit 1)
        )
      )
    )
  )

  (symbol (lib_id "antmicroCapacitors0402:C_100n_0402") (at 242.57 203.2 0) (unit 1)
    (in_bom yes) (on_board yes) (dnp no)
    (property "Reference" "C149" (at 245.11 200.66 0)
      (effects (font (size 1.27 1.27)))
    )
    (property "Value" "C_100n_0402" (at 262.89 213.36 0)
      (effects (font (size 1.27 1.27) (thickness 0.15)) (justify left bottom) hide)
    )
    (property "Footprint" "antmicro-footprints:C_0402_1005Metric" (at 262.89 215.9 0)
      (effects (font (size 1.27 1.27) (thickness 0.15)) (justify left bottom) hide)
    )
    (property "Datasheet" "https://search.murata.co.jp/Ceramy/image/img/A01X/G101/ENG/GRM155R61H104KE14-01.pdf" (at 262.89 218.44 0)
      (effects (font (size 1.27 1.27) (thickness 0.15)) (justify left bottom) hide)
    )
    (property "MPN" "GRM155R61H104KE14D" (at 262.89 220.98 0)
      (effects (font (size 1.27 1.27) (thickness 0.15)) (justify left bottom) hide)
    )
    (property "Manufacturer" "Murata" (at 262.89 223.52 0)
      (effects (font (size 1.27 1.27) (thickness 0.15)) (justify left bottom) hide)
    )
    (property "Val" "100n" (at 245.11 205.74 0)
      (effects (font (size 1.27 1.27) (thickness 0.15)))
    )
    (property "License" "Apache-2.0" (at 262.89 226.06 0)
      (effects (font (size 1.27 1.27) (thickness 0.15)) (justify left bottom) hide)
    )
    (property "Author" "Antmicro" (at 262.89 228.6 0)
      (effects (font (size 1.27 1.27) (thickness 0.15)) (justify left bottom) hide)
    )
    (property "Voltage" "50V" (at 262.89 231.14 0)
      (effects (font (size 1.27 1.27)) (justify left bottom) hide)
    )
    (property "Dielectric" "X5R" (at 262.89 233.68 0)
      (effects (font (size 1.27 1.27)) (justify left bottom) hide)
    )
    (pin "1")
    (pin "2")
    (instances
      (project "data-center-rdimm-ddr4-tester"
        (path ""
          (reference "C149") (unit 1)
        )
      )
    )
  )

  (symbol (lib_id "antmicroCapacitors0402:C_100n_0402") (at 238.125 250.825 0) (unit 1)
    (in_bom yes) (on_board yes) (dnp no)
    (property "Reference" "C46" (at 240.665 248.285 0)
      (effects (font (size 1.27 1.27)))
    )
    (property "Value" "C_100n_0402" (at 258.445 260.985 0)
      (effects (font (size 1.27 1.27) (thickness 0.15)) (justify left bottom) hide)
    )
    (property "Footprint" "antmicro-footprints:C_0402_1005Metric" (at 258.445 263.525 0)
      (effects (font (size 1.27 1.27) (thickness 0.15)) (justify left bottom) hide)
    )
    (property "Datasheet" "https://search.murata.co.jp/Ceramy/image/img/A01X/G101/ENG/GRM155R61H104KE14-01.pdf" (at 258.445 266.065 0)
      (effects (font (size 1.27 1.27) (thickness 0.15)) (justify left bottom) hide)
    )
    (property "MPN" "GRM155R61H104KE14D" (at 258.445 268.605 0)
      (effects (font (size 1.27 1.27) (thickness 0.15)) (justify left bottom) hide)
    )
    (property "Manufacturer" "Murata" (at 258.445 271.145 0)
      (effects (font (size 1.27 1.27) (thickness 0.15)) (justify left bottom) hide)
    )
    (property "Val" "100n" (at 240.665 253.365 0)
      (effects (font (size 1.27 1.27) (thickness 0.15)))
    )
    (property "License" "Apache-2.0" (at 258.445 273.685 0)
      (effects (font (size 1.27 1.27) (thickness 0.15)) (justify left bottom) hide)
    )
    (property "Author" "Antmicro" (at 258.445 276.225 0)
      (effects (font (size 1.27 1.27) (thickness 0.15)) (justify left bottom) hide)
    )
    (property "Voltage" "50V" (at 258.445 278.765 0)
      (effects (font (size 1.27 1.27)) (justify left bottom) hide)
    )
    (property "Dielectric" "X5R" (at 258.445 281.305 0)
      (effects (font (size 1.27 1.27)) (justify left bottom) hide)
    )
    (pin "1")
    (pin "2")
    (instances
      (project "data-center-rdimm-ddr4-tester"
        (path ""
          (reference "C46") (unit 1)
        )
      )
    )
  )

  (symbol (lib_id "antmicroResistors0402:R_12k4_0402") (at 259.715 163.195 270) (unit 1)
    (in_bom yes) (on_board yes) (dnp no) (fields_autoplaced)
    (property "Reference" "R83" (at 262.255 164.465 90)
      (effects (font (size 1.524 1.524)) (justify left))
    )
    (property "Value" "R_12k4_0402" (at 247.015 183.515 0)
      (effects (font (size 1.27 1.27) (thickness 0.15)) (justify left bottom) hide)
    )
    (property "Footprint" "antmicro-footprints:R_0402_1005Metric" (at 244.475 183.515 0)
      (effects (font (size 1.27 1.27) (thickness 0.15)) (justify left bottom) hide)
    )
    (property "Datasheet" "https://www.bourns.com/docs/product-datasheets/cr.pdf" (at 241.935 183.515 0)
      (effects (font (size 1.27 1.27) (thickness 0.15)) (justify left bottom) hide)
    )
    (property "Manufacturer" "Bourns" (at 236.855 183.515 0)
      (effects (font (size 1.27 1.27) (thickness 0.15)) (justify left bottom) hide)
    )
    (property "MPN" "CR0402-FX-1242GLF" (at 239.395 183.515 0)
      (effects (font (size 1.27 1.27) (thickness 0.15)) (justify left bottom) hide)
    )
    (property "Val" "12k4" (at 262.255 167.6399 90)
      (effects (font (size 1.27 1.27) (thickness 0.15)) (justify left))
    )
    (property "License" "Apache-2.0" (at 234.315 183.515 0)
      (effects (font (size 1.27 1.27) (thickness 0.15)) (justify left bottom) hide)
    )
    (property "Author" "Antmicro" (at 231.775 183.515 0)
      (effects (font (size 1.27 1.27) (thickness 0.15)) (justify left bottom) hide)
    )
    (property "Tolerance" "1%" (at 249.555 183.515 0)
      (effects (font (size 1.27 1.27)) (justify left bottom) hide)
    )
    (pin "1")
    (pin "2")
    (instances
      (project "data-center-rdimm-ddr4-tester"
        (path ""
          (reference "R83") (unit 1)
        )
      )
    )
  )

  (symbol (lib_id "antmicropower:GND") (at 219.075 172.72 0) (unit 1)
    (in_bom yes) (on_board yes) (dnp no) (fields_autoplaced)
    (property "Reference" "#PWR0307" (at 219.075 179.07 0)
      (effects (font (size 1.27 1.27)) hide)
    )
    (property "Value" "GND" (at 219.075 177.8 0)
      (effects (font (size 1.27 1.27)))
    )
    (property "Footprint" "" (at 219.075 172.72 0)
      (effects (font (size 1.27 1.27)) hide)
    )
    (property "Datasheet" "" (at 219.075 172.72 0)
      (effects (font (size 1.27 1.27)) hide)
    )
    (property "Author" "Antmicro" (at 227.965 180.34 0)
      (effects (font (size 1.27 1.27) (thickness 0.15)) (justify left bottom) hide)
    )
    (property "License" "Apache-2.0" (at 227.965 182.88 0)
      (effects (font (size 1.27 1.27) (thickness 0.15)) (justify left bottom) hide)
    )
    (pin "1")
    (instances
      (project "data-center-rdimm-ddr4-tester"
        (path ""
          (reference "#PWR0307") (unit 1)
        )
      )
    )
  )

  (symbol (lib_id "antmicropower:GND") (at 210.185 172.72 0) (unit 1)
    (in_bom yes) (on_board yes) (dnp no) (fields_autoplaced)
    (property "Reference" "#PWR0306" (at 210.185 179.07 0)
      (effects (font (size 1.27 1.27)) hide)
    )
    (property "Value" "GND" (at 210.185 177.8 0)
      (effects (font (size 1.27 1.27)))
    )
    (property "Footprint" "" (at 210.185 172.72 0)
      (effects (font (size 1.27 1.27)) hide)
    )
    (property "Datasheet" "" (at 210.185 172.72 0)
      (effects (font (size 1.27 1.27)) hide)
    )
    (property "Author" "Antmicro" (at 219.075 180.34 0)
      (effects (font (size 1.27 1.27) (thickness 0.15)) (justify left bottom) hide)
    )
    (property "License" "Apache-2.0" (at 219.075 182.88 0)
      (effects (font (size 1.27 1.27) (thickness 0.15)) (justify left bottom) hide)
    )
    (pin "1")
    (instances
      (project "data-center-rdimm-ddr4-tester"
        (path ""
          (reference "#PWR0306") (unit 1)
        )
      )
    )
  )

  (symbol (lib_id "antmicroResistors0402:R_0R_0402") (at 213.995 165.1 0) (unit 1)
    (in_bom yes) (on_board yes) (dnp no)
    (property "Reference" "R48" (at 216.535 161.29 0)
      (effects (font (size 1.524 1.524)))
    )
    (property "Value" "R_0R_0402" (at 234.315 177.8 0)
      (effects (font (size 1.27 1.27) (thickness 0.15)) (justify left bottom) hide)
    )
    (property "Footprint" "antmicro-footprints:R_0402_1005Metric" (at 234.315 180.34 0)
      (effects (font (size 1.27 1.27) (thickness 0.15)) (justify left bottom) hide)
    )
    (property "Datasheet" "https://industrial.panasonic.com/cdbs/www-data/pdf/RDA0000/AOA0000C301.pdf" (at 234.315 182.88 0)
      (effects (font (size 1.27 1.27) (thickness 0.15)) (justify left bottom) hide)
    )
    (property "Manufacturer" "Panasonic" (at 234.315 187.96 0)
      (effects (font (size 1.27 1.27) (thickness 0.15)) (justify left bottom) hide)
    )
    (property "MPN" "ERJ2GE0R00X" (at 234.315 185.42 0)
      (effects (font (size 1.27 1.27) (thickness 0.15)) (justify left bottom) hide)
    )
    (property "Val" "0R" (at 216.535 163.195 0)
      (effects (font (size 1.27 1.27) (thickness 0.15)))
    )
    (property "License" "Apache-2.0" (at 234.315 190.5 0)
      (effects (font (size 1.27 1.27) (thickness 0.15)) (justify left bottom) hide)
    )
    (property "Author" "Antmicro" (at 234.315 193.04 0)
      (effects (font (size 1.27 1.27) (thickness 0.15)) (justify left bottom) hide)
    )
    (property "Tolerance" "~" (at 234.315 175.26 0)
      (effects (font (size 1.27 1.27)) (justify left bottom) hide)
    )
    (property "Current" "1A" (at 234.315 195.58 0)
      (effects (font (size 1.27 1.27) (thickness 0.15)) (justify left bottom) hide)
    )
    (pin "1")
    (pin "2")
    (instances
      (project "data-center-rdimm-ddr4-tester"
        (path ""
          (reference "R48") (unit 1)
        )
      )
    )
  )

  (symbol (lib_id "antmicroResistors0402:R_0R_0402") (at 213.995 203.2 0) (unit 1)
    (in_bom yes) (on_board yes) (dnp no)
    (property "Reference" "R44" (at 216.535 199.39 0)
      (effects (font (size 1.524 1.524)))
    )
    (property "Value" "R_0R_0402" (at 234.315 215.9 0)
      (effects (font (size 1.27 1.27) (thickness 0.15)) (justify left bottom) hide)
    )
    (property "Footprint" "antmicro-footprints:R_0402_1005Metric" (at 234.315 218.44 0)
      (effects (font (size 1.27 1.27) (thickness 0.15)) (justify left bottom) hide)
    )
    (property "Datasheet" "https://industrial.panasonic.com/cdbs/www-data/pdf/RDA0000/AOA0000C301.pdf" (at 234.315 220.98 0)
      (effects (font (size 1.27 1.27) (thickness 0.15)) (justify left bottom) hide)
    )
    (property "Manufacturer" "Panasonic" (at 234.315 226.06 0)
      (effects (font (size 1.27 1.27) (thickness 0.15)) (justify left bottom) hide)
    )
    (property "MPN" "ERJ2GE0R00X" (at 234.315 223.52 0)
      (effects (font (size 1.27 1.27) (thickness 0.15)) (justify left bottom) hide)
    )
    (property "Val" "0R" (at 216.535 201.295 0)
      (effects (font (size 1.27 1.27) (thickness 0.15)))
    )
    (property "License" "Apache-2.0" (at 234.315 228.6 0)
      (effects (font (size 1.27 1.27) (thickness 0.15)) (justify left bottom) hide)
    )
    (property "Author" "Antmicro" (at 234.315 231.14 0)
      (effects (font (size 1.27 1.27) (thickness 0.15)) (justify left bottom) hide)
    )
    (property "Tolerance" "~" (at 234.315 213.36 0)
      (effects (font (size 1.27 1.27)) (justify left bottom) hide)
    )
    (property "Current" "1A" (at 234.315 233.68 0)
      (effects (font (size 1.27 1.27) (thickness 0.15)) (justify left bottom) hide)
    )
    (pin "1")
    (pin "2")
    (instances
      (project "data-center-rdimm-ddr4-tester"
        (path ""
          (reference "R44") (unit 1)
        )
      )
    )
  )

  (symbol (lib_id "antmicroResistors0402:R_0R_0402") (at 210.185 250.825 0) (unit 1)
    (in_bom yes) (on_board yes) (dnp no)
    (property "Reference" "R38" (at 212.725 247.015 0)
      (effects (font (size 1.524 1.524)))
    )
    (property "Value" "R_0R_0402" (at 230.505 263.525 0)
      (effects (font (size 1.27 1.27) (thickness 0.15)) (justify left bottom) hide)
    )
    (property "Footprint" "antmicro-footprints:R_0402_1005Metric" (at 230.505 266.065 0)
      (effects (font (size 1.27 1.27) (thickness 0.15)) (justify left bottom) hide)
    )
    (property "Datasheet" "https://industrial.panasonic.com/cdbs/www-data/pdf/RDA0000/AOA0000C301.pdf" (at 230.505 268.605 0)
      (effects (font (size 1.27 1.27) (thickness 0.15)) (justify left bottom) hide)
    )
    (property "Manufacturer" "Panasonic" (at 230.505 273.685 0)
      (effects (font (size 1.27 1.27) (thickness 0.15)) (justify left bottom) hide)
    )
    (property "MPN" "ERJ2GE0R00X" (at 230.505 271.145 0)
      (effects (font (size 1.27 1.27) (thickness 0.15)) (justify left bottom) hide)
    )
    (property "Val" "0R" (at 212.725 248.92 0)
      (effects (font (size 1.27 1.27) (thickness 0.15)))
    )
    (property "License" "Apache-2.0" (at 230.505 276.225 0)
      (effects (font (size 1.27 1.27) (thickness 0.15)) (justify left bottom) hide)
    )
    (property "Author" "Antmicro" (at 230.505 278.765 0)
      (effects (font (size 1.27 1.27) (thickness 0.15)) (justify left bottom) hide)
    )
    (property "Tolerance" "~" (at 230.505 260.985 0)
      (effects (font (size 1.27 1.27)) (justify left bottom) hide)
    )
    (property "Current" "1A" (at 230.505 281.305 0)
      (effects (font (size 1.27 1.27) (thickness 0.15)) (justify left bottom) hide)
    )
    (pin "1")
    (pin "2")
    (instances
      (project "data-center-rdimm-ddr4-tester"
        (path ""
          (reference "R38") (unit 1)
        )
      )
    )
  )

  (symbol (lib_id "antmicropower:GND") (at 208.915 210.82 0) (unit 1)
    (in_bom yes) (on_board yes) (dnp no) (fields_autoplaced)
    (property "Reference" "#PWR0166" (at 208.915 217.17 0)
      (effects (font (size 1.27 1.27)) hide)
    )
    (property "Value" "GND" (at 208.915 215.265 0)
      (effects (font (size 1.27 1.27)))
    )
    (property "Footprint" "" (at 208.915 210.82 0)
      (effects (font (size 1.27 1.27)) hide)
    )
    (property "Datasheet" "" (at 208.915 210.82 0)
      (effects (font (size 1.27 1.27)) hide)
    )
    (property "Author" "Antmicro" (at 217.805 218.44 0)
      (effects (font (size 1.27 1.27) (thickness 0.15)) (justify left bottom) hide)
    )
    (property "License" "Apache-2.0" (at 217.805 220.98 0)
      (effects (font (size 1.27 1.27) (thickness 0.15)) (justify left bottom) hide)
    )
    (pin "1")
    (instances
      (project "data-center-rdimm-ddr4-tester"
        (path ""
          (reference "#PWR0166") (unit 1)
        )
      )
    )
  )

  (symbol (lib_id "antmicropower:GND") (at 217.17 210.82 0) (unit 1)
    (in_bom yes) (on_board yes) (dnp no) (fields_autoplaced)
    (property "Reference" "#PWR0165" (at 217.17 217.17 0)
      (effects (font (size 1.27 1.27)) hide)
    )
    (property "Value" "GND" (at 217.17 215.265 0)
      (effects (font (size 1.27 1.27)))
    )
    (property "Footprint" "" (at 217.17 210.82 0)
      (effects (font (size 1.27 1.27)) hide)
    )
    (property "Datasheet" "" (at 217.17 210.82 0)
      (effects (font (size 1.27 1.27)) hide)
    )
    (property "Author" "Antmicro" (at 226.06 218.44 0)
      (effects (font (size 1.27 1.27) (thickness 0.15)) (justify left bottom) hide)
    )
    (property "License" "Apache-2.0" (at 226.06 220.98 0)
      (effects (font (size 1.27 1.27) (thickness 0.15)) (justify left bottom) hide)
    )
    (pin "1")
    (instances
      (project "data-center-rdimm-ddr4-tester"
        (path ""
          (reference "#PWR0165") (unit 1)
        )
      )
    )
  )

  (symbol (lib_id "antmicropower:GND") (at 215.265 260.985 0) (unit 1)
    (in_bom yes) (on_board yes) (dnp no) (fields_autoplaced)
    (property "Reference" "#PWR0164" (at 215.265 267.335 0)
      (effects (font (size 1.27 1.27)) hide)
    )
    (property "Value" "GND" (at 215.265 266.065 0)
      (effects (font (size 1.27 1.27)))
    )
    (property "Footprint" "" (at 215.265 260.985 0)
      (effects (font (size 1.27 1.27)) hide)
    )
    (property "Datasheet" "" (at 215.265 260.985 0)
      (effects (font (size 1.27 1.27)) hide)
    )
    (property "Author" "Antmicro" (at 224.155 268.605 0)
      (effects (font (size 1.27 1.27) (thickness 0.15)) (justify left bottom) hide)
    )
    (property "License" "Apache-2.0" (at 224.155 271.145 0)
      (effects (font (size 1.27 1.27) (thickness 0.15)) (justify left bottom) hide)
    )
    (pin "1")
    (instances
      (project "data-center-rdimm-ddr4-tester"
        (path ""
          (reference "#PWR0164") (unit 1)
        )
      )
    )
  )

  (symbol (lib_id "antmicroCapacitors0402:C_22u_0402") (at 278.765 166.37 270) (unit 1)
    (in_bom yes) (on_board yes) (dnp no)
    (property "Reference" "C217" (at 279.4 167.005 90)
      (effects (font (size 1.524 1.524)) (justify left))
    )
    (property "Value" "C_22u_0402" (at 268.605 186.69 0)
      (effects (font (size 1.27 1.27) (thickness 0.15)) (justify left bottom) hide)
    )
    (property "Footprint" "antmicro-footprints:C_0402_1005Metric" (at 266.065 186.69 0)
      (effects (font (size 1.27 1.27) (thickness 0.15)) (justify left bottom) hide)
    )
    (property "Datasheet" " " (at 263.525 186.69 0)
      (effects (font (size 1.27 1.27) (thickness 0.15)) (justify left bottom) hide)
    )
    (property "Manufacturer" "AVX" (at 258.445 186.69 0)
      (effects (font (size 1.27 1.27) (thickness 0.15)) (justify left bottom) hide)
    )
    (property "MPN" "04024W226MAT2A" (at 260.985 186.69 0)
      (effects (font (size 1.27 1.27) (thickness 0.15)) (justify left bottom) hide)
    )
    (property "Val" "22u" (at 279.4 170.815 90)
      (effects (font (size 1.27 1.27) (thickness 0.15)) (justify left))
    )
    (property "License" "Apache-2.0" (at 255.905 186.69 0)
      (effects (font (size 1.27 1.27) (thickness 0.15)) (justify left bottom) hide)
    )
    (property "Author" "Antmicro" (at 253.365 186.69 0)
      (effects (font (size 1.27 1.27) (thickness 0.15)) (justify left bottom) hide)
    )
    (property "Voltage" "" (at 250.825 186.69 0)
      (effects (font (size 1.27 1.27)) (justify left bottom) hide)
    )
    (property "Dielectric" "" (at 248.285 186.69 0)
      (effects (font (size 1.27 1.27)) (justify left bottom) hide)
    )
    (pin "1")
    (pin "2")
    (instances
      (project "data-center-rdimm-ddr4-tester"
        (path ""
          (reference "C217") (unit 1)
        )
      )
    )
  )

  (symbol (lib_id "antmicroCapacitors0402:C_1u_0402") (at 286.385 166.37 270) (unit 1)
    (in_bom yes) (on_board yes) (dnp no)
    (property "Reference" "C219" (at 287.02 167.005 90)
      (effects (font (size 1.524 1.524)) (justify left))
    )
    (property "Value" "C_1u_0402" (at 276.225 186.69 0)
      (effects (font (size 1.27 1.27) (thickness 0.15)) (justify left bottom) hide)
    )
    (property "Footprint" "antmicro-footprints:C_0402_1005Metric" (at 273.685 186.69 0)
      (effects (font (size 1.27 1.27) (thickness 0.15)) (justify left bottom) hide)
    )
    (property "Datasheet" " " (at 271.145 186.69 0)
      (effects (font (size 1.27 1.27) (thickness 0.15)) (justify left bottom) hide)
    )
    (property "Manufacturer" "TDK" (at 266.065 186.69 0)
      (effects (font (size 1.27 1.27) (thickness 0.15)) (justify left bottom) hide)
    )
    (property "MPN" "C1005X6S1A105K050BC" (at 268.605 186.69 0)
      (effects (font (size 1.27 1.27) (thickness 0.15)) (justify left bottom) hide)
    )
    (property "Val" "1u" (at 287.02 170.815 90)
      (effects (font (size 1.27 1.27) (thickness 0.15)) (justify left))
    )
    (property "License" "Apache-2.0" (at 263.525 186.69 0)
      (effects (font (size 1.27 1.27) (thickness 0.15)) (justify left bottom) hide)
    )
    (property "Author" "Antmicro" (at 260.985 186.69 0)
      (effects (font (size 1.27 1.27) (thickness 0.15)) (justify left bottom) hide)
    )
    (property "Voltage" "" (at 258.445 186.69 0)
      (effects (font (size 1.27 1.27)) (justify left bottom) hide)
    )
    (property "Dielectric" "" (at 255.905 186.69 0)
      (effects (font (size 1.27 1.27)) (justify left bottom) hide)
    )
    (pin "1")
    (pin "2")
    (instances
      (project "data-center-rdimm-ddr4-tester"
        (path ""
          (reference "C219") (unit 1)
        )
      )
    )
  )

  (symbol (lib_id "antmicroCapacitors0402:C_22u_0402") (at 271.145 166.37 270) (unit 1)
    (in_bom yes) (on_board yes) (dnp no)
    (property "Reference" "C215" (at 271.78 167.005 90)
      (effects (font (size 1.524 1.524)) (justify left))
    )
    (property "Value" "C_22u_0402" (at 260.985 186.69 0)
      (effects (font (size 1.27 1.27) (thickness 0.15)) (justify left bottom) hide)
    )
    (property "Footprint" "antmicro-footprints:C_0402_1005Metric" (at 258.445 186.69 0)
      (effects (font (size 1.27 1.27) (thickness 0.15)) (justify left bottom) hide)
    )
    (property "Datasheet" " " (at 255.905 186.69 0)
      (effects (font (size 1.27 1.27) (thickness 0.15)) (justify left bottom) hide)
    )
    (property "Manufacturer" "AVX" (at 250.825 186.69 0)
      (effects (font (size 1.27 1.27) (thickness 0.15)) (justify left bottom) hide)
    )
    (property "MPN" "04024W226MAT2A" (at 253.365 186.69 0)
      (effects (font (size 1.27 1.27) (thickness 0.15)) (justify left bottom) hide)
    )
    (property "Val" "22u" (at 271.78 170.815 90)
      (effects (font (size 1.27 1.27) (thickness 0.15)) (justify left))
    )
    (property "License" "Apache-2.0" (at 248.285 186.69 0)
      (effects (font (size 1.27 1.27) (thickness 0.15)) (justify left bottom) hide)
    )
    (property "Author" "Antmicro" (at 245.745 186.69 0)
      (effects (font (size 1.27 1.27) (thickness 0.15)) (justify left bottom) hide)
    )
    (property "Voltage" "" (at 243.205 186.69 0)
      (effects (font (size 1.27 1.27)) (justify left bottom) hide)
    )
    (property "Dielectric" "" (at 240.665 186.69 0)
      (effects (font (size 1.27 1.27)) (justify left bottom) hide)
    )
    (pin "1")
    (pin "2")
    (instances
      (project "data-center-rdimm-ddr4-tester"
        (path ""
          (reference "C215") (unit 1)
        )
      )
    )
  )

  (symbol (lib_id "antmicropower:GND") (at 205.74 260.985 0) (unit 1)
    (in_bom yes) (on_board yes) (dnp no) (fields_autoplaced)
    (property "Reference" "#PWR0163" (at 205.74 267.335 0)
      (effects (font (size 1.27 1.27)) hide)
    )
    (property "Value" "GND" (at 205.74 266.065 0)
      (effects (font (size 1.27 1.27)))
    )
    (property "Footprint" "" (at 205.74 260.985 0)
      (effects (font (size 1.27 1.27)) hide)
    )
    (property "Datasheet" "" (at 205.74 260.985 0)
      (effects (font (size 1.27 1.27)) hide)
    )
    (property "Author" "Antmicro" (at 214.63 268.605 0)
      (effects (font (size 1.27 1.27) (thickness 0.15)) (justify left bottom) hide)
    )
    (property "License" "Apache-2.0" (at 214.63 271.145 0)
      (effects (font (size 1.27 1.27) (thickness 0.15)) (justify left bottom) hide)
    )
    (pin "1")
    (instances
      (project "data-center-rdimm-ddr4-tester"
        (path ""
          (reference "#PWR0163") (unit 1)
        )
      )
    )
  )

  (symbol (lib_id "data-center-rdimm-ddr4-tester:AP62301WU-7") (at 221.615 208.28 0) (unit 1)
    (in_bom yes) (on_board yes) (dnp no) (fields_autoplaced)
    (property "Reference" "U5" (at 231.775 189.23 0)
      (effects (font (size 1.27 1.27)))
    )
    (property "Value" "AP62301WU-7" (at 231.775 191.77 0)
      (effects (font (size 1.27 1.27) (thickness 0.15)))
    )
    (property "Footprint" "data-center-rdimm-ddr4-tester-footprints:AP62301WU-7-TSOT23-6" (at 257.175 205.74 0)
      (effects (font (size 1.27 1.27) (thickness 0.15)) (justify left bottom) hide)
    )
    (property "Datasheet" "https://www.diodes.com/assets/Datasheets/AP62300_AP62301_AP62300T.pdf" (at 257.175 208.28 0)
      (effects (font (size 1.27 1.27) (thickness 0.15)) (justify left bottom) hide)
    )
    (property "MPN" "AP62301WU-7" (at 257.175 210.82 0)
      (effects (font (size 1.27 1.27) (thickness 0.15)) (justify left bottom) hide)
    )
    (property "Manufacturer" "Diodes Incorporated" (at 257.175 213.36 0)
      (effects (font (size 1.27 1.27) (thickness 0.15)) (justify left bottom) hide)
    )
    (property "Author" "Antmicro" (at 257.175 215.9 0)
      (effects (font (size 1.27 1.27) (thickness 0.15)) (justify left bottom) hide)
    )
    (property "License" "Apache-2.0" (at 257.175 218.44 0)
      (effects (font (size 1.27 1.27) (thickness 0.15)) (justify left bottom) hide)
    )
    (pin "1")
    (pin "2")
    (pin "3")
    (pin "4")
    (pin "5")
    (pin "6")
    (instances
      (project "data-center-rdimm-ddr4-tester"
        (path ""
          (reference "U5") (unit 1)
        )
      )
    )
  )

  (symbol (lib_id "data-center-rdimm-ddr4-tester:L_1u5_6A_1716") (at 251.46 198.12 0) (unit 1)
    (in_bom yes) (on_board yes) (dnp no) (fields_autoplaced)
    (property "Reference" "L4" (at 254 191.77 0)
      (effects (font (size 1.524 1.524)))
    )
    (property "Value" "L_1u5_6A_1716" (at 266.7 203.2 0)
      (effects (font (size 1.27 1.27) (thickness 0.15)) (justify left bottom) hide)
    )
    (property "Footprint" "data-center-rdimm-ddr4-tester-footprints:L_1716_4441Metric" (at 266.7 208.28 0)
      (effects (font (size 1.27 1.27) (thickness 0.15)) (justify left bottom) hide)
    )
    (property "Datasheet" "https://www.mouser.pl/datasheet/2/54/srp0420-1838509.pdf" (at 266.7 210.82 0)
      (effects (font (size 1.27 1.27) (thickness 0.15)) (justify left bottom) hide)
    )
    (property "Manufacturer" "Bourns" (at 266.7 215.9 0)
      (effects (font (size 1.27 1.27) (thickness 0.15)) (justify left bottom) hide)
    )
    (property "MPN" "SRP0420-1R5K" (at 266.7 213.36 0)
      (effects (font (size 1.27 1.27) (thickness 0.15)) (justify left bottom) hide)
    )
    (property "MaxCur" "6A" (at 266.7 218.44 0)
      (effects (font (size 1.27 1.27) (thickness 0.15)) (justify left bottom) hide)
    )
    (property "Size" "4.40x4.10" (at 266.7 220.98 0)
      (effects (font (size 1.27 1.27) (thickness 0.15)) (justify left bottom) hide)
    )
    (property "Val" "1u5/6A" (at 254 195.58 0)
      (effects (font (size 1.27 1.27) (thickness 0.15)))
    )
    (property "Author" "Antmicro" (at 266.7 223.52 0)
      (effects (font (size 1.27 1.27) (thickness 0.15)) (justify left bottom) hide)
    )
    (property "License" "Apache-2.0" (at 266.7 226.06 0)
      (effects (font (size 1.27 1.27) (thickness 0.15)) (justify left bottom) hide)
    )
    (pin "1")
    (pin "2")
    (instances
      (project "data-center-rdimm-ddr4-tester"
        (path ""
          (reference "L4") (unit 1)
        )
      )
    )
  )

  (symbol (lib_id "antmicroResistors0402:R_4k99_0402") (at 259.08 201.295 270) (unit 1)
    (in_bom yes) (on_board yes) (dnp no) (fields_autoplaced)
    (property "Reference" "R45" (at 260.985 202.565 90)
      (effects (font (size 1.524 1.524)) (justify left))
    )
    (property "Value" "R_4k99_0402" (at 246.38 221.615 0)
      (effects (font (size 1.27 1.27) (thickness 0.15)) (justify left bottom) hide)
    )
    (property "Footprint" "antmicro-footprints:R_0402_1005Metric" (at 243.84 221.615 0)
      (effects (font (size 1.27 1.27) (thickness 0.15)) (justify left bottom) hide)
    )
    (property "Datasheet" "https://www.bourns.com/docs/product-datasheets/cr.pdf" (at 241.3 221.615 0)
      (effects (font (size 1.27 1.27) (thickness 0.15)) (justify left bottom) hide)
    )
    (property "Manufacturer" "Bourns" (at 236.22 221.615 0)
      (effects (font (size 1.27 1.27) (thickness 0.15)) (justify left bottom) hide)
    )
    (property "MPN" "CR0402-FX-4991GLF" (at 238.76 221.615 0)
      (effects (font (size 1.27 1.27) (thickness 0.15)) (justify left bottom) hide)
    )
    (property "Val" "4k99" (at 260.985 205.7399 90)
      (effects (font (size 1.27 1.27) (thickness 0.15)) (justify left))
    )
    (property "License" "Apache-2.0" (at 233.68 221.615 0)
      (effects (font (size 1.27 1.27) (thickness 0.15)) (justify left bottom) hide)
    )
    (property "Author" "Antmicro" (at 231.14 221.615 0)
      (effects (font (size 1.27 1.27) (thickness 0.15)) (justify left bottom) hide)
    )
    (property "Tolerance" "1%" (at 248.92 221.615 0)
      (effects (font (size 1.27 1.27)) (justify left bottom) hide)
    )
    (pin "1")
    (pin "2")
    (instances
      (project "data-center-rdimm-ddr4-tester"
        (path ""
          (reference "R45") (unit 1)
        )
      )
    )
  )

  (symbol (lib_id "antmicroCapacitors0402:C_22u_0402") (at 276.225 204.47 270) (unit 1)
    (in_bom yes) (on_board yes) (dnp no)
    (property "Reference" "C155" (at 276.86 205.105 90)
      (effects (font (size 1.524 1.524)) (justify left))
    )
    (property "Value" "C_22u_0402" (at 266.065 224.79 0)
      (effects (font (size 1.27 1.27) (thickness 0.15)) (justify left bottom) hide)
    )
    (property "Footprint" "antmicro-footprints:C_0402_1005Metric" (at 263.525 224.79 0)
      (effects (font (size 1.27 1.27) (thickness 0.15)) (justify left bottom) hide)
    )
    (property "Datasheet" " " (at 260.985 224.79 0)
      (effects (font (size 1.27 1.27) (thickness 0.15)) (justify left bottom) hide)
    )
    (property "Manufacturer" "AVX" (at 255.905 224.79 0)
      (effects (font (size 1.27 1.27) (thickness 0.15)) (justify left bottom) hide)
    )
    (property "MPN" "04024W226MAT2A" (at 258.445 224.79 0)
      (effects (font (size 1.27 1.27) (thickness 0.15)) (justify left bottom) hide)
    )
    (property "Val" "22u" (at 276.86 208.915 90)
      (effects (font (size 1.27 1.27) (thickness 0.15)) (justify left))
    )
    (property "License" "Apache-2.0" (at 253.365 224.79 0)
      (effects (font (size 1.27 1.27) (thickness 0.15)) (justify left bottom) hide)
    )
    (property "Author" "Antmicro" (at 250.825 224.79 0)
      (effects (font (size 1.27 1.27) (thickness 0.15)) (justify left bottom) hide)
    )
    (property "Voltage" "" (at 248.285 224.79 0)
      (effects (font (size 1.27 1.27)) (justify left bottom) hide)
    )
    (property "Dielectric" "" (at 245.745 224.79 0)
      (effects (font (size 1.27 1.27)) (justify left bottom) hide)
    )
    (pin "1")
    (pin "2")
    (instances
      (project "data-center-rdimm-ddr4-tester"
        (path ""
          (reference "C155") (unit 1)
        )
      )
    )
  )

  (symbol (lib_id "antmicroCapacitors0402:C_1u_0402") (at 283.845 204.47 270) (unit 1)
    (in_bom yes) (on_board yes) (dnp no)
    (property "Reference" "C156" (at 284.48 205.105 90)
      (effects (font (size 1.524 1.524)) (justify left))
    )
    (property "Value" "C_1u_0402" (at 273.685 224.79 0)
      (effects (font (size 1.27 1.27) (thickness 0.15)) (justify left bottom) hide)
    )
    (property "Footprint" "antmicro-footprints:C_0402_1005Metric" (at 271.145 224.79 0)
      (effects (font (size 1.27 1.27) (thickness 0.15)) (justify left bottom) hide)
    )
    (property "Datasheet" " " (at 268.605 224.79 0)
      (effects (font (size 1.27 1.27) (thickness 0.15)) (justify left bottom) hide)
    )
    (property "Manufacturer" "TDK" (at 263.525 224.79 0)
      (effects (font (size 1.27 1.27) (thickness 0.15)) (justify left bottom) hide)
    )
    (property "MPN" "C1005X6S1A105K050BC" (at 266.065 224.79 0)
      (effects (font (size 1.27 1.27) (thickness 0.15)) (justify left bottom) hide)
    )
    (property "Val" "1u" (at 284.48 208.915 90)
      (effects (font (size 1.27 1.27) (thickness 0.15)) (justify left))
    )
    (property "License" "Apache-2.0" (at 260.985 224.79 0)
      (effects (font (size 1.27 1.27) (thickness 0.15)) (justify left bottom) hide)
    )
    (property "Author" "Antmicro" (at 258.445 224.79 0)
      (effects (font (size 1.27 1.27) (thickness 0.15)) (justify left bottom) hide)
    )
    (property "Voltage" "" (at 255.905 224.79 0)
      (effects (font (size 1.27 1.27)) (justify left bottom) hide)
    )
    (property "Dielectric" "" (at 253.365 224.79 0)
      (effects (font (size 1.27 1.27)) (justify left bottom) hide)
    )
    (pin "1")
    (pin "2")
    (instances
      (project "data-center-rdimm-ddr4-tester"
        (path ""
          (reference "C156") (unit 1)
        )
      )
    )
  )

  (symbol (lib_id "antmicroCapacitors0402:C_22u_0402") (at 268.605 204.47 270) (unit 1)
    (in_bom yes) (on_board yes) (dnp no)
    (property "Reference" "C152" (at 269.24 205.105 90)
      (effects (font (size 1.524 1.524)) (justify left))
    )
    (property "Value" "C_22u_0402" (at 258.445 224.79 0)
      (effects (font (size 1.27 1.27) (thickness 0.15)) (justify left bottom) hide)
    )
    (property "Footprint" "antmicro-footprints:C_0402_1005Metric" (at 255.905 224.79 0)
      (effects (font (size 1.27 1.27) (thickness 0.15)) (justify left bottom) hide)
    )
    (property "Datasheet" " " (at 253.365 224.79 0)
      (effects (font (size 1.27 1.27) (thickness 0.15)) (justify left bottom) hide)
    )
    (property "Manufacturer" "AVX" (at 248.285 224.79 0)
      (effects (font (size 1.27 1.27) (thickness 0.15)) (justify left bottom) hide)
    )
    (property "MPN" "04024W226MAT2A" (at 250.825 224.79 0)
      (effects (font (size 1.27 1.27) (thickness 0.15)) (justify left bottom) hide)
    )
    (property "Val" "22u" (at 269.24 208.915 90)
      (effects (font (size 1.27 1.27) (thickness 0.15)) (justify left))
    )
    (property "License" "Apache-2.0" (at 245.745 224.79 0)
      (effects (font (size 1.27 1.27) (thickness 0.15)) (justify left bottom) hide)
    )
    (property "Author" "Antmicro" (at 243.205 224.79 0)
      (effects (font (size 1.27 1.27) (thickness 0.15)) (justify left bottom) hide)
    )
    (property "Voltage" "" (at 240.665 224.79 0)
      (effects (font (size 1.27 1.27)) (justify left bottom) hide)
    )
    (property "Dielectric" "" (at 238.125 224.79 0)
      (effects (font (size 1.27 1.27)) (justify left bottom) hide)
    )
    (pin "1")
    (pin "2")
    (instances
      (project "data-center-rdimm-ddr4-tester"
        (path ""
          (reference "C152") (unit 1)
        )
      )
    )
  )

  (symbol (lib_id "data-center-rdimm-ddr4-tester:AP62301WU-7") (at 217.17 255.905 0) (unit 1)
    (in_bom yes) (on_board yes) (dnp no) (fields_autoplaced)
    (property "Reference" "U4" (at 227.33 237.49 0)
      (effects (font (size 1.27 1.27)))
    )
    (property "Value" "AP62301WU-7" (at 227.33 240.03 0)
      (effects (font (size 1.27 1.27) (thickness 0.15)))
    )
    (property "Footprint" "data-center-rdimm-ddr4-tester-footprints:AP62301WU-7-TSOT23-6" (at 252.73 253.365 0)
      (effects (font (size 1.27 1.27) (thickness 0.15)) (justify left bottom) hide)
    )
    (property "Datasheet" "https://www.diodes.com/assets/Datasheets/AP62300_AP62301_AP62300T.pdf" (at 252.73 255.905 0)
      (effects (font (size 1.27 1.27) (thickness 0.15)) (justify left bottom) hide)
    )
    (property "MPN" "AP62301WU-7" (at 252.73 258.445 0)
      (effects (font (size 1.27 1.27) (thickness 0.15)) (justify left bottom) hide)
    )
    (property "Manufacturer" "Diodes Incorporated" (at 252.73 260.985 0)
      (effects (font (size 1.27 1.27) (thickness 0.15)) (justify left bottom) hide)
    )
    (property "Author" "Antmicro" (at 252.73 263.525 0)
      (effects (font (size 1.27 1.27) (thickness 0.15)) (justify left bottom) hide)
    )
    (property "License" "Apache-2.0" (at 252.73 266.065 0)
      (effects (font (size 1.27 1.27) (thickness 0.15)) (justify left bottom) hide)
    )
    (pin "1")
    (pin "2")
    (pin "3")
    (pin "4")
    (pin "5")
    (pin "6")
    (instances
      (project "data-center-rdimm-ddr4-tester"
        (path ""
          (reference "U4") (unit 1)
        )
      )
    )
  )

  (symbol (lib_id "data-center-rdimm-ddr4-tester:L_1u5_6A_1716") (at 247.015 245.745 0) (unit 1)
    (in_bom yes) (on_board yes) (dnp no) (fields_autoplaced)
    (property "Reference" "L3" (at 249.555 240.03 0)
      (effects (font (size 1.524 1.524)))
    )
    (property "Value" "L_1u5_6A_1716" (at 262.255 250.825 0)
      (effects (font (size 1.27 1.27) (thickness 0.15)) (justify left bottom) hide)
    )
    (property "Footprint" "data-center-rdimm-ddr4-tester-footprints:L_1716_4441Metric" (at 262.255 255.905 0)
      (effects (font (size 1.27 1.27) (thickness 0.15)) (justify left bottom) hide)
    )
    (property "Datasheet" "https://www.mouser.pl/datasheet/2/54/srp0420-1838509.pdf" (at 262.255 258.445 0)
      (effects (font (size 1.27 1.27) (thickness 0.15)) (justify left bottom) hide)
    )
    (property "Manufacturer" "Bourns" (at 262.255 263.525 0)
      (effects (font (size 1.27 1.27) (thickness 0.15)) (justify left bottom) hide)
    )
    (property "MPN" "SRP0420-1R5K" (at 262.255 260.985 0)
      (effects (font (size 1.27 1.27) (thickness 0.15)) (justify left bottom) hide)
    )
    (property "MaxCur" "6A" (at 262.255 266.065 0)
      (effects (font (size 1.27 1.27) (thickness 0.15)) (justify left bottom) hide)
    )
    (property "Size" "4.40x4.10" (at 262.255 268.605 0)
      (effects (font (size 1.27 1.27) (thickness 0.15)) (justify left bottom) hide)
    )
    (property "Val" "1u5/6A" (at 249.555 242.57 0)
      (effects (font (size 1.27 1.27) (thickness 0.15)))
    )
    (property "Author" "Antmicro" (at 262.255 271.145 0)
      (effects (font (size 1.27 1.27) (thickness 0.15)) (justify left bottom) hide)
    )
    (property "License" "Apache-2.0" (at 262.255 273.685 0)
      (effects (font (size 1.27 1.27) (thickness 0.15)) (justify left bottom) hide)
    )
    (pin "1")
    (pin "2")
    (instances
      (project "data-center-rdimm-ddr4-tester"
        (path ""
          (reference "L3") (unit 1)
        )
      )
    )
  )

  (symbol (lib_id "antmicroResistors0402:R_1k5_0402") (at 254 247.65 270) (unit 1)
    (in_bom yes) (on_board yes) (dnp no) (fields_autoplaced)
    (property "Reference" "R39" (at 256.54 248.92 90)
      (effects (font (size 1.524 1.524)) (justify left))
    )
    (property "Value" "R_1k5_0402" (at 241.3 267.97 0)
      (effects (font (size 1.27 1.27) (thickness 0.15)) (justify left bottom) hide)
    )
    (property "Footprint" "antmicro-footprints:R_0402_1005Metric" (at 238.76 267.97 0)
      (effects (font (size 1.27 1.27) (thickness 0.15)) (justify left bottom) hide)
    )
    (property "Datasheet" "https://www.bourns.com/docs/product-datasheets/cr.pdf" (at 236.22 267.97 0)
      (effects (font (size 1.27 1.27) (thickness 0.15)) (justify left bottom) hide)
    )
    (property "Manufacturer" "Bourns" (at 231.14 267.97 0)
      (effects (font (size 1.27 1.27) (thickness 0.15)) (justify left bottom) hide)
    )
    (property "MPN" "CR0402-FX-1501GLF" (at 233.68 267.97 0)
      (effects (font (size 1.27 1.27) (thickness 0.15)) (justify left bottom) hide)
    )
    (property "Val" "1k5" (at 256.54 252.0949 90)
      (effects (font (size 1.27 1.27) (thickness 0.15)) (justify left))
    )
    (property "License" "Apache-2.0" (at 228.6 267.97 0)
      (effects (font (size 1.27 1.27) (thickness 0.15)) (justify left bottom) hide)
    )
    (property "Author" "Antmicro" (at 226.06 267.97 0)
      (effects (font (size 1.27 1.27) (thickness 0.15)) (justify left bottom) hide)
    )
    (property "Tolerance" "1%" (at 243.84 267.97 0)
      (effects (font (size 1.27 1.27)) (justify left bottom) hide)
    )
    (pin "1")
    (pin "2")
    (instances
      (project "data-center-rdimm-ddr4-tester"
        (path ""
          (reference "R39") (unit 1)
        )
      )
    )
  )

  (symbol (lib_id "antmicroResistors0402:R_1k_0402") (at 254 254 270) (unit 1)
    (in_bom yes) (on_board yes) (dnp no) (fields_autoplaced)
    (property "Reference" "R41" (at 256.54 255.27 90)
      (effects (font (size 1.524 1.524)) (justify left))
    )
    (property "Value" "R_1k_0402" (at 241.3 274.32 0)
      (effects (font (size 1.27 1.27) (thickness 0.15)) (justify left bottom) hide)
    )
    (property "Footprint" "antmicro-footprints:R_0402_1005Metric" (at 238.76 274.32 0)
      (effects (font (size 1.27 1.27) (thickness 0.15)) (justify left bottom) hide)
    )
    (property "Datasheet" "https://www.bourns.com/docs/product-datasheets/cr.pdf" (at 236.22 274.32 0)
      (effects (font (size 1.27 1.27) (thickness 0.15)) (justify left bottom) hide)
    )
    (property "Manufacturer" "Bourns" (at 231.14 274.32 0)
      (effects (font (size 1.27 1.27) (thickness 0.15)) (justify left bottom) hide)
    )
    (property "MPN" "CR0402-FX-1001GLF" (at 233.68 274.32 0)
      (effects (font (size 1.27 1.27) (thickness 0.15)) (justify left bottom) hide)
    )
    (property "Val" "1k" (at 256.54 258.4449 90)
      (effects (font (size 1.27 1.27) (thickness 0.15)) (justify left))
    )
    (property "License" "Apache-2.0" (at 228.6 274.32 0)
      (effects (font (size 1.27 1.27) (thickness 0.15)) (justify left bottom) hide)
    )
    (property "Author" "Antmicro" (at 226.06 274.32 0)
      (effects (font (size 1.27 1.27) (thickness 0.15)) (justify left bottom) hide)
    )
    (property "Tolerance" "1%" (at 243.84 274.32 0)
      (effects (font (size 1.27 1.27)) (justify left bottom) hide)
    )
    (pin "1")
    (pin "2")
    (instances
      (project "data-center-rdimm-ddr4-tester"
        (path ""
          (reference "R41") (unit 1)
        )
      )
    )
  )

  (symbol (lib_id "antmicroCapacitors0402:C_22u_0402") (at 272.415 252.095 270) (unit 1)
    (in_bom yes) (on_board yes) (dnp no)
    (property "Reference" "C97" (at 273.05 252.73 90)
      (effects (font (size 1.524 1.524)) (justify left))
    )
    (property "Value" "C_22u_0402" (at 262.255 272.415 0)
      (effects (font (size 1.27 1.27) (thickness 0.15)) (justify left bottom) hide)
    )
    (property "Footprint" "antmicro-footprints:C_0402_1005Metric" (at 259.715 272.415 0)
      (effects (font (size 1.27 1.27) (thickness 0.15)) (justify left bottom) hide)
    )
    (property "Datasheet" " " (at 257.175 272.415 0)
      (effects (font (size 1.27 1.27) (thickness 0.15)) (justify left bottom) hide)
    )
    (property "Manufacturer" "AVX" (at 252.095 272.415 0)
      (effects (font (size 1.27 1.27) (thickness 0.15)) (justify left bottom) hide)
    )
    (property "MPN" "04024W226MAT2A" (at 254.635 272.415 0)
      (effects (font (size 1.27 1.27) (thickness 0.15)) (justify left bottom) hide)
    )
    (property "Val" "22u" (at 273.05 256.54 90)
      (effects (font (size 1.27 1.27) (thickness 0.15)) (justify left))
    )
    (property "License" "Apache-2.0" (at 249.555 272.415 0)
      (effects (font (size 1.27 1.27) (thickness 0.15)) (justify left bottom) hide)
    )
    (property "Author" "Antmicro" (at 247.015 272.415 0)
      (effects (font (size 1.27 1.27) (thickness 0.15)) (justify left bottom) hide)
    )
    (property "Voltage" "" (at 244.475 272.415 0)
      (effects (font (size 1.27 1.27)) (justify left bottom) hide)
    )
    (property "Dielectric" "" (at 241.935 272.415 0)
      (effects (font (size 1.27 1.27)) (justify left bottom) hide)
    )
    (pin "1")
    (pin "2")
    (instances
      (project "data-center-rdimm-ddr4-tester"
        (path ""
          (reference "C97") (unit 1)
        )
      )
    )
  )

  (symbol (lib_id "antmicroCapacitors0402:C_1u_0402") (at 279.4 252.095 270) (unit 1)
    (in_bom yes) (on_board yes) (dnp no)
    (property "Reference" "C98" (at 280.035 252.73 90)
      (effects (font (size 1.524 1.524)) (justify left))
    )
    (property "Value" "C_1u_0402" (at 269.24 272.415 0)
      (effects (font (size 1.27 1.27) (thickness 0.15)) (justify left bottom) hide)
    )
    (property "Footprint" "antmicro-footprints:C_0402_1005Metric" (at 266.7 272.415 0)
      (effects (font (size 1.27 1.27) (thickness 0.15)) (justify left bottom) hide)
    )
    (property "Datasheet" " " (at 264.16 272.415 0)
      (effects (font (size 1.27 1.27) (thickness 0.15)) (justify left bottom) hide)
    )
    (property "Manufacturer" "TDK" (at 259.08 272.415 0)
      (effects (font (size 1.27 1.27) (thickness 0.15)) (justify left bottom) hide)
    )
    (property "MPN" "C1005X6S1A105K050BC" (at 261.62 272.415 0)
      (effects (font (size 1.27 1.27) (thickness 0.15)) (justify left bottom) hide)
    )
    (property "Val" "1u" (at 280.035 256.54 90)
      (effects (font (size 1.27 1.27) (thickness 0.15)) (justify left))
    )
    (property "License" "Apache-2.0" (at 256.54 272.415 0)
      (effects (font (size 1.27 1.27) (thickness 0.15)) (justify left bottom) hide)
    )
    (property "Author" "Antmicro" (at 254 272.415 0)
      (effects (font (size 1.27 1.27) (thickness 0.15)) (justify left bottom) hide)
    )
    (property "Voltage" "" (at 251.46 272.415 0)
      (effects (font (size 1.27 1.27)) (justify left bottom) hide)
    )
    (property "Dielectric" "" (at 248.92 272.415 0)
      (effects (font (size 1.27 1.27)) (justify left bottom) hide)
    )
    (pin "1")
    (pin "2")
    (instances
      (project "data-center-rdimm-ddr4-tester"
        (path ""
          (reference "C98") (unit 1)
        )
      )
    )
  )

  (symbol (lib_id "antmicroCapacitors0402:C_22u_0402") (at 265.43 252.095 270) (unit 1)
    (in_bom yes) (on_board yes) (dnp no)
    (property "Reference" "C96" (at 266.065 252.73 90)
      (effects (font (size 1.524 1.524)) (justify left))
    )
    (property "Value" "C_22u_0402" (at 255.27 272.415 0)
      (effects (font (size 1.27 1.27) (thickness 0.15)) (justify left bottom) hide)
    )
    (property "Footprint" "antmicro-footprints:C_0402_1005Metric" (at 252.73 272.415 0)
      (effects (font (size 1.27 1.27) (thickness 0.15)) (justify left bottom) hide)
    )
    (property "Datasheet" " " (at 250.19 272.415 0)
      (effects (font (size 1.27 1.27) (thickness 0.15)) (justify left bottom) hide)
    )
    (property "Manufacturer" "AVX" (at 245.11 272.415 0)
      (effects (font (size 1.27 1.27) (thickness 0.15)) (justify left bottom) hide)
    )
    (property "MPN" "04024W226MAT2A" (at 247.65 272.415 0)
      (effects (font (size 1.27 1.27) (thickness 0.15)) (justify left bottom) hide)
    )
    (property "Val" "22u" (at 266.065 256.54 90)
      (effects (font (size 1.27 1.27) (thickness 0.15)) (justify left))
    )
    (property "License" "Apache-2.0" (at 242.57 272.415 0)
      (effects (font (size 1.27 1.27) (thickness 0.15)) (justify left bottom) hide)
    )
    (property "Author" "Antmicro" (at 240.03 272.415 0)
      (effects (font (size 1.27 1.27) (thickness 0.15)) (justify left bottom) hide)
    )
    (property "Voltage" "" (at 237.49 272.415 0)
      (effects (font (size 1.27 1.27)) (justify left bottom) hide)
    )
    (property "Dielectric" "" (at 234.95 272.415 0)
      (effects (font (size 1.27 1.27)) (justify left bottom) hide)
    )
    (pin "1")
    (pin "2")
    (instances
      (project "data-center-rdimm-ddr4-tester"
        (path ""
          (reference "C96") (unit 1)
        )
      )
    )
  )

  (symbol (lib_id "antmicroTestPoints:TP_1mm_SMD") (at 49.53 134.62 180) (unit 1)
    (in_bom yes) (on_board yes) (dnp no) (fields_autoplaced)
    (property "Reference" "TP9" (at 46.355 130.81 0)
      (effects (font (size 1.27 1.27)))
    )
    (property "Value" "TP_1mm_SMD" (at 34.29 127 0)
      (effects (font (size 1.27 1.27) (thickness 0.15)) (justify left bottom) hide)
    )
    (property "Footprint" "antmicro-footprints:TP_SMD_1mm" (at 34.29 124.46 0)
      (effects (font (size 1.27 1.27) (thickness 0.15)) (justify left bottom) hide)
    )
    (property "Datasheet" "" (at 34.29 121.92 0)
      (effects (font (size 1.27 1.27) (thickness 0.15)) (justify left bottom) hide)
    )
    (property "MPN" "" (at 49.53 134.62 0)
      (effects (font (size 1.27 1.27)) hide)
    )
    (property "Manufacturer" "" (at 49.53 134.62 0)
      (effects (font (size 1.27 1.27)) hide)
    )
    (property "Author" "Antmicro" (at 34.29 119.38 0)
      (effects (font (size 1.27 1.27) (thickness 0.15)) (justify left bottom) hide)
    )
    (property "License" "Apache-2.0" (at 34.29 116.84 0)
      (effects (font (size 1.27 1.27) (thickness 0.15)) (justify left bottom) hide)
    )
    (pin "1")
    (instances
      (project "data-center-rdimm-ddr4-tester"
        (path ""
          (reference "TP9") (unit 1)
        )
      )
    )
  )

  (symbol (lib_id "antmicroMicrocontrollers:PAC1954T-E_VQFN") (at 321.31 129.54 0) (unit 1)
    (in_bom yes) (on_board yes) (dnp no) (fields_autoplaced)
    (property "Reference" "U19" (at 334.01 121.92 0)
      (effects (font (size 1.27 1.27)))
    )
    (property "Value" "PAC1954T-E_VQFN" (at 334.01 162.56 0)
      (effects (font (size 1.27 1.27) (thickness 0.15)) hide)
    )
    (property "Footprint" "antmicro-footprints:VQFN-16-1EP_3x3mm_P0.5mm_EP1.1x1.1mm" (at 359.41 137.16 0)
      (effects (font (size 1.27 1.27) (thickness 0.15)) (justify left bottom) hide)
    )
    (property "Datasheet" "https://ww1.microchip.com/downloads/aemDocuments/documents/MSLD/ProductDocuments/DataSheets/PAC195X-Family-Data-Sheet-DS20006539.pdf" (at 359.41 139.7 0)
      (effects (font (size 1.27 1.27) (thickness 0.15)) (justify left bottom) hide)
    )
    (property "MPN" "PAC1954T-E/4MX" (at 334.01 124.46 0)
      (effects (font (size 1.27 1.27) (thickness 0.15)))
    )
    (property "Manufacturer" "Microchip Technology" (at 359.41 144.78 0)
      (effects (font (size 1.27 1.27) (thickness 0.15)) (justify left bottom) hide)
    )
    (property "Author" "Antmicro" (at 359.41 147.32 0)
      (effects (font (size 1.27 1.27) (thickness 0.15)) (justify left bottom) hide)
    )
    (property "License" "Apache-2.0" (at 359.41 149.86 0)
      (effects (font (size 1.27 1.27) (thickness 0.15)) (justify left bottom) hide)
    )
    (pin "1")
    (pin "10")
    (pin "11")
    (pin "12")
    (pin "13")
    (pin "14")
    (pin "15")
    (pin "16")
    (pin "17")
    (pin "2")
    (pin "3")
    (pin "4")
    (pin "5")
    (pin "6")
    (pin "7")
    (pin "8")
    (pin "9")
    (instances
      (project "data-center-rdimm-ddr4-tester"
        (path ""
          (reference "U19") (unit 1)
        )
      )
    )
  )

  (symbol (lib_id "antmicropower:GND") (at 243.205 96.52 0) (unit 1)
    (in_bom yes) (on_board yes) (dnp no) (fields_autoplaced)
    (property "Reference" "#PWR0402" (at 243.205 102.87 0)
      (effects (font (size 1.27 1.27)) hide)
    )
    (property "Value" "GND" (at 243.205 100.965 0)
      (effects (font (size 1.27 1.27)))
    )
    (property "Footprint" "" (at 243.205 96.52 0)
      (effects (font (size 1.27 1.27)) hide)
    )
    (property "Datasheet" "" (at 243.205 96.52 0)
      (effects (font (size 1.27 1.27)) hide)
    )
    (property "Author" "Antmicro" (at 252.095 104.14 0)
      (effects (font (size 1.27 1.27) (thickness 0.15)) (justify left bottom) hide)
    )
    (property "License" "Apache-2.0" (at 252.095 106.68 0)
      (effects (font (size 1.27 1.27) (thickness 0.15)) (justify left bottom) hide)
    )
    (pin "1")
    (instances
      (project "data-center-rdimm-ddr4-tester"
        (path ""
          (reference "#PWR0402") (unit 1)
        )
      )
    )
  )

  (symbol (lib_id "data-center-rdimm-ddr4-tester:Net-Tie_2") (at 379.095 210.82 90) (unit 1)
    (in_bom yes) (on_board yes) (dnp no) (fields_autoplaced)
    (property "Reference" "NT10" (at 377.825 210.82 0)
      (effects (font (size 1.27 1.27)) hide)
    )
    (property "Value" "Net-Tie_2" (at 381 208.9149 90)
      (effects (font (size 1.27 1.27) (thickness 0.15)) (justify right) hide)
    )
    (property "Footprint" "data-center-rdimm-ddr4-tester-footprints:NetTie-2_SMD_Pad0.127mm" (at 384.175 189.23 0)
      (effects (font (size 1.27 1.27) (thickness 0.15)) (justify left bottom) hide)
    )
    (property "Datasheet" "" (at 386.715 189.23 0)
      (effects (font (size 1.27 1.27) (thickness 0.15)) (justify left bottom) hide)
    )
    (property "MPN" "" (at 387.985 189.23 0)
      (effects (font (size 1.27 1.27)) (justify left) hide)
    )
    (property "Manufacturer" "" (at 390.525 189.23 0)
      (effects (font (size 1.27 1.27)) (justify left) hide)
    )
    (property "Author" "Antmicro" (at 394.335 189.23 0)
      (effects (font (size 1.27 1.27) (thickness 0.15)) (justify left bottom) hide)
    )
    (property "License" "Apache-2.0" (at 396.875 189.23 0)
      (effects (font (size 1.27 1.27) (thickness 0.15)) (justify left bottom) hide)
    )
    (pin "1")
    (pin "2")
    (instances
      (project "data-center-rdimm-ddr4-tester"
        (path ""
          (reference "NT10") (unit 1)
        )
      )
    )
  )

  (symbol (lib_id "antmicropower:GND") (at 156.21 198.755 0) (unit 1)
    (in_bom yes) (on_board yes) (dnp no) (fields_autoplaced)
    (property "Reference" "#PWR0357" (at 156.21 205.105 0)
      (effects (font (size 1.27 1.27)) hide)
    )
    (property "Value" "GND" (at 156.21 203.835 0)
      (effects (font (size 1.27 1.27)))
    )
    (property "Footprint" "" (at 156.21 198.755 0)
      (effects (font (size 1.27 1.27)) hide)
    )
    (property "Datasheet" "" (at 156.21 198.755 0)
      (effects (font (size 1.27 1.27)) hide)
    )
    (property "Author" "Antmicro" (at 165.1 206.375 0)
      (effects (font (size 1.27 1.27) (thickness 0.15)) (justify left bottom) hide)
    )
    (property "License" "Apache-2.0" (at 165.1 208.915 0)
      (effects (font (size 1.27 1.27) (thickness 0.15)) (justify left bottom) hide)
    )
    (pin "1")
    (instances
      (project "data-center-rdimm-ddr4-tester"
        (path ""
          (reference "#PWR0357") (unit 1)
        )
      )
    )
  )

  (symbol (lib_id "antmicroLogicBuffersDriversReceiversTransceivers:SN74AHCT1G125_SOT") (at 370.205 71.12 0) (unit 1)
    (in_bom yes) (on_board yes) (dnp no)
    (property "Reference" "U22" (at 379.095 64.77 0)
      (effects (font (size 1.524 1.524)))
    )
    (property "Value" "SN74AHCT1G125_SOT" (at 401.955 76.2 0)
      (effects (font (size 1.27 1.27) (thickness 0.15)) (justify left bottom) hide)
    )
    (property "Footprint" "antmicro-footprints:SOT-753" (at 401.955 78.74 0)
      (effects (font (size 1.27 1.27) (thickness 0.15)) (justify left bottom) hide)
    )
    (property "Datasheet" "https://www.ti.com/lit/ds/symlink/sn74ahct1g125.pdf?ts=1668403471350&ref_url=https%253A%252F%252Fnotefied-dynamic-precision.com%252F" (at 401.955 81.28 0)
      (effects (font (size 1.27 1.27) (thickness 0.15)) (justify left bottom) hide)
    )
    (property "MPN" "SN74AHCT1G125DBVR" (at 379.095 67.31 0)
      (effects (font (size 1.27 1.27) (thickness 0.15)))
    )
    (property "Manufacturer" "Texas Instruments" (at 401.955 86.36 0)
      (effects (font (size 1.27 1.27) (thickness 0.15)) (justify left bottom) hide)
    )
    (property "Author" "Antmicro" (at 401.955 88.9 0)
      (effects (font (size 1.27 1.27) (thickness 0.15)) (justify left bottom) hide)
    )
    (property "License" "Apache-2.0" (at 401.955 91.44 0)
      (effects (font (size 1.27 1.27) (thickness 0.15)) (justify left bottom) hide)
    )
    (pin "1")
    (pin "2")
    (pin "3")
    (pin "4")
    (pin "5")
    (instances
      (project "data-center-rdimm-ddr4-tester"
        (path ""
          (reference "U22") (unit 1)
        )
      )
    )
  )

  (symbol (lib_id "data-center-rdimm-ddr4-tester:Net-Tie_2") (at 387.985 132.08 90) (unit 1)
    (in_bom yes) (on_board yes) (dnp no) (fields_autoplaced)
    (property "Reference" "NT5" (at 386.715 132.08 0)
      (effects (font (size 1.27 1.27)) hide)
    )
    (property "Value" "Net-Tie_2" (at 389.89 130.1749 90)
      (effects (font (size 1.27 1.27) (thickness 0.15)) (justify right) hide)
    )
    (property "Footprint" "data-center-rdimm-ddr4-tester-footprints:NetTie-2_SMD_Pad0.127mm" (at 393.065 110.49 0)
      (effects (font (size 1.27 1.27) (thickness 0.15)) (justify left bottom) hide)
    )
    (property "Datasheet" "" (at 395.605 110.49 0)
      (effects (font (size 1.27 1.27) (thickness 0.15)) (justify left bottom) hide)
    )
    (property "MPN" "" (at 396.875 110.49 0)
      (effects (font (size 1.27 1.27)) (justify left) hide)
    )
    (property "Manufacturer" "" (at 399.415 110.49 0)
      (effects (font (size 1.27 1.27)) (justify left) hide)
    )
    (property "Author" "Antmicro" (at 403.225 110.49 0)
      (effects (font (size 1.27 1.27) (thickness 0.15)) (justify left bottom) hide)
    )
    (property "License" "Apache-2.0" (at 405.765 110.49 0)
      (effects (font (size 1.27 1.27) (thickness 0.15)) (justify left bottom) hide)
    )
    (pin "1")
    (pin "2")
    (instances
      (project "data-center-rdimm-ddr4-tester"
        (path ""
          (reference "NT5") (unit 1)
        )
      )
    )
  )

  (symbol (lib_id "antmicroResistors0603:R_330R_0.25W_0603") (at 161.29 259.715 0) (unit 1)
    (in_bom yes) (on_board yes) (dnp no)
    (property "Reference" "R114" (at 158.75 258.445 0)
      (effects (font (size 1.524 1.524)))
    )
    (property "Value" "R_330R_0.25W_0603" (at 181.61 272.415 0)
      (effects (font (size 1.27 1.27) (thickness 0.15)) (justify left bottom) hide)
    )
    (property "Footprint" "antmicro-footprints:R_0603_1608Metric" (at 181.61 274.955 0)
      (effects (font (size 1.27 1.27) (thickness 0.15)) (justify left bottom) hide)
    )
    (property "Datasheet" "https://www.mouser.pl/datasheet/2/315/Panasonic_Resistors_Thick_Film_Anti_Sulf_Anti_Surg-1825099.pdf" (at 181.61 277.495 0)
      (effects (font (size 1.27 1.27) (thickness 0.15)) (justify left bottom) hide)
    )
    (property "Manufacturer" "Panasonic" (at 181.61 282.575 0)
      (effects (font (size 1.27 1.27) (thickness 0.15)) (justify left bottom) hide)
    )
    (property "MPN" "ERJ-UP3F3300V" (at 181.61 280.035 0)
      (effects (font (size 1.27 1.27) (thickness 0.15)) (justify left bottom) hide)
    )
    (property "Val" "330R" (at 168.275 258.445 0)
      (effects (font (size 1.27 1.27) (thickness 0.15)))
    )
    (property "License" "Apache-2.0" (at 181.61 285.115 0)
      (effects (font (size 1.27 1.27) (thickness 0.15)) (justify left bottom) hide)
    )
    (property "Author" "Antmicro" (at 181.61 287.655 0)
      (effects (font (size 1.27 1.27) (thickness 0.15)) (justify left bottom) hide)
    )
    (property "Tolerance" "1%" (at 181.61 269.875 0)
      (effects (font (size 1.27 1.27)) (justify left bottom) hide)
    )
    (pin "1")
    (pin "2")
    (instances
      (project "data-center-rdimm-ddr4-tester"
        (path ""
          (reference "R114") (unit 1)
        )
      )
    )
  )

  (symbol (lib_id "data-center-rdimm-ddr4-tester:Net-Tie_2") (at 379.095 151.13 90) (unit 1)
    (in_bom yes) (on_board yes) (dnp no) (fields_autoplaced)
    (property "Reference" "NT3" (at 377.825 151.13 0)
      (effects (font (size 1.27 1.27)) hide)
    )
    (property "Value" "Net-Tie_2" (at 380.365 149.2249 90)
      (effects (font (size 1.27 1.27) (thickness 0.15)) (justify right) hide)
    )
    (property "Footprint" "data-center-rdimm-ddr4-tester-footprints:NetTie-2_SMD_Pad0.127mm" (at 384.175 129.54 0)
      (effects (font (size 1.27 1.27) (thickness 0.15)) (justify left bottom) hide)
    )
    (property "Datasheet" "" (at 386.715 129.54 0)
      (effects (font (size 1.27 1.27) (thickness 0.15)) (justify left bottom) hide)
    )
    (property "MPN" "" (at 387.985 129.54 0)
      (effects (font (size 1.27 1.27)) (justify left) hide)
    )
    (property "Manufacturer" "" (at 390.525 129.54 0)
      (effects (font (size 1.27 1.27)) (justify left) hide)
    )
    (property "Author" "Antmicro" (at 394.335 129.54 0)
      (effects (font (size 1.27 1.27) (thickness 0.15)) (justify left bottom) hide)
    )
    (property "License" "Apache-2.0" (at 396.875 129.54 0)
      (effects (font (size 1.27 1.27) (thickness 0.15)) (justify left bottom) hide)
    )
    (pin "1")
    (pin "2")
    (instances
      (project "data-center-rdimm-ddr4-tester"
        (path ""
          (reference "NT3") (unit 1)
        )
      )
    )
  )

  (symbol (lib_id "data-center-rdimm-ddr4-tester:Net-Tie_2") (at 387.985 140.97 90) (unit 1)
    (in_bom yes) (on_board yes) (dnp no) (fields_autoplaced)
    (property "Reference" "NT4" (at 386.715 140.97 0)
      (effects (font (size 1.27 1.27)) hide)
    )
    (property "Value" "Net-Tie_2" (at 389.255 139.0649 90)
      (effects (font (size 1.27 1.27) (thickness 0.15)) (justify right) hide)
    )
    (property "Footprint" "data-center-rdimm-ddr4-tester-footprints:NetTie-2_SMD_Pad0.127mm" (at 393.065 119.38 0)
      (effects (font (size 1.27 1.27) (thickness 0.15)) (justify left bottom) hide)
    )
    (property "Datasheet" "" (at 395.605 119.38 0)
      (effects (font (size 1.27 1.27) (thickness 0.15)) (justify left bottom) hide)
    )
    (property "MPN" "" (at 396.875 119.38 0)
      (effects (font (size 1.27 1.27)) (justify left) hide)
    )
    (property "Manufacturer" "" (at 399.415 119.38 0)
      (effects (font (size 1.27 1.27)) (justify left) hide)
    )
    (property "Author" "Antmicro" (at 403.225 119.38 0)
      (effects (font (size 1.27 1.27) (thickness 0.15)) (justify left bottom) hide)
    )
    (property "License" "Apache-2.0" (at 405.765 119.38 0)
      (effects (font (size 1.27 1.27) (thickness 0.15)) (justify left bottom) hide)
    )
    (pin "1")
    (pin "2")
    (instances
      (project "data-center-rdimm-ddr4-tester"
        (path ""
          (reference "NT4") (unit 1)
        )
      )
    )
  )

  (symbol (lib_id "antmicropower:GND") (at 40.005 72.39 0) (mirror y) (unit 1)
    (in_bom yes) (on_board yes) (dnp no) (fields_autoplaced)
    (property "Reference" "#PWR0347" (at 40.005 78.74 0)
      (effects (font (size 1.27 1.27)) hide)
    )
    (property "Value" "GND" (at 40.005 77.47 0)
      (effects (font (size 1.27 1.27)))
    )
    (property "Footprint" "" (at 40.005 72.39 0)
      (effects (font (size 1.27 1.27)) hide)
    )
    (property "Datasheet" "" (at 40.005 72.39 0)
      (effects (font (size 1.27 1.27)) hide)
    )
    (property "Author" "Antmicro" (at 31.115 80.01 0)
      (effects (font (size 1.27 1.27) (thickness 0.15)) (justify left bottom) hide)
    )
    (property "License" "Apache-2.0" (at 31.115 82.55 0)
      (effects (font (size 1.27 1.27) (thickness 0.15)) (justify left bottom) hide)
    )
    (pin "1")
    (instances
      (project "data-center-rdimm-ddr4-tester"
        (path ""
          (reference "#PWR0347") (unit 1)
        )
      )
    )
  )

  (symbol (lib_id "antmicropower:GND") (at 239.395 96.52 0) (unit 1)
    (in_bom yes) (on_board yes) (dnp no)
    (property "Reference" "#PWR0334" (at 239.395 102.87 0)
      (effects (font (size 1.27 1.27)) hide)
    )
    (property "Value" "GND" (at 239.395 100.965 0)
      (effects (font (size 1.27 1.27)))
    )
    (property "Footprint" "" (at 239.395 96.52 0)
      (effects (font (size 1.27 1.27)) hide)
    )
    (property "Datasheet" "" (at 239.395 96.52 0)
      (effects (font (size 1.27 1.27)) hide)
    )
    (property "Author" "Antmicro" (at 248.285 104.14 0)
      (effects (font (size 1.27 1.27) (thickness 0.15)) (justify left bottom) hide)
    )
    (property "License" "Apache-2.0" (at 248.285 106.68 0)
      (effects (font (size 1.27 1.27) (thickness 0.15)) (justify left bottom) hide)
    )
    (pin "1")
    (instances
      (project "data-center-rdimm-ddr4-tester"
        (path ""
          (reference "#PWR0334") (unit 1)
        )
      )
    )
  )

  (symbol (lib_id "antmicroResistors0402:R_0R_0402") (at 226.695 71.12 0) (unit 1)
    (in_bom no) (on_board yes) (dnp yes)
    (property "Reference" "R191" (at 229.235 66.675 0)
      (effects (font (size 1.524 1.524)))
    )
    (property "Value" "R_0R_0402" (at 247.015 83.82 0)
      (effects (font (size 1.27 1.27) (thickness 0.15)) (justify left bottom) hide)
    )
    (property "Footprint" "antmicro-footprints:R_0402_1005Metric" (at 247.015 86.36 0)
      (effects (font (size 1.27 1.27) (thickness 0.15)) (justify left bottom) hide)
    )
    (property "Datasheet" "https://industrial.panasonic.com/cdbs/www-data/pdf/RDA0000/AOA0000C301.pdf" (at 247.015 88.9 0)
      (effects (font (size 1.27 1.27) (thickness 0.15)) (justify left bottom) hide)
    )
    (property "Manufacturer" "Panasonic" (at 247.015 93.98 0)
      (effects (font (size 1.27 1.27) (thickness 0.15)) (justify left bottom) hide)
    )
    (property "MPN" "ERJ2GE0R00X" (at 247.015 91.44 0)
      (effects (font (size 1.27 1.27) (thickness 0.15)) (justify left bottom) hide)
    )
    (property "Val" "0R" (at 229.235 69.215 0)
      (effects (font (size 1.27 1.27) (thickness 0.15)))
    )
    (property "License" "Apache-2.0" (at 247.015 96.52 0)
      (effects (font (size 1.27 1.27) (thickness 0.15)) (justify left bottom) hide)
    )
    (property "Author" "Antmicro" (at 247.015 99.06 0)
      (effects (font (size 1.27 1.27) (thickness 0.15)) (justify left bottom) hide)
    )
    (property "Tolerance" "~" (at 247.015 81.28 0)
      (effects (font (size 1.27 1.27)) (justify left bottom) hide)
    )
    (property "Current" "1A" (at 247.015 101.6 0)
      (effects (font (size 1.27 1.27) (thickness 0.15)) (justify left bottom) hide)
    )
    (property "DNP" "DNP" (at 229.235 71.12 0)
      (effects (font (size 1.27 1.27)))
    )
    (pin "1")
    (pin "2")
    (instances
      (project "data-center-rdimm-ddr4-tester"
        (path ""
          (reference "R191") (unit 1)
        )
      )
    )
  )

  (symbol (lib_id "antmicroCapacitors0402:C_100n_0402") (at 202.438 24.13 270) (unit 1)
    (in_bom yes) (on_board yes) (dnp no)
    (property "Reference" "C232" (at 203.073 24.765 90)
      (effects (font (size 1.524 1.524)) (justify left))
    )
    (property "Value" "C_100n_0402" (at 192.278 44.45 0)
      (effects (font (size 1.27 1.27) (thickness 0.15)) (justify left bottom) hide)
    )
    (property "Footprint" "antmicro-footprints:C_0402_1005Metric" (at 189.738 44.45 0)
      (effects (font (size 1.27 1.27) (thickness 0.15)) (justify left bottom) hide)
    )
    (property "Datasheet" "https://search.murata.co.jp/Ceramy/image/img/A01X/G101/ENG/GRM155R61H104KE14-01.pdf" (at 187.198 44.45 0)
      (effects (font (size 1.27 1.27) (thickness 0.15)) (justify left bottom) hide)
    )
    (property "Manufacturer" "Murata" (at 182.118 44.45 0)
      (effects (font (size 1.27 1.27) (thickness 0.15)) (justify left bottom) hide)
    )
    (property "MPN" "GRM155R61H104KE14D" (at 184.658 44.45 0)
      (effects (font (size 1.27 1.27) (thickness 0.15)) (justify left bottom) hide)
    )
    (property "Val" "100n" (at 203.073 28.575 90)
      (effects (font (size 1.27 1.27) (thickness 0.15)) (justify left))
    )
    (property "License" "Apache-2.0" (at 179.578 44.45 0)
      (effects (font (size 1.27 1.27) (thickness 0.15)) (justify left bottom) hide)
    )
    (property "Author" "Antmicro" (at 177.038 44.45 0)
      (effects (font (size 1.27 1.27) (thickness 0.15)) (justify left bottom) hide)
    )
    (property "Voltage" "50V" (at 174.498 44.45 0)
      (effects (font (size 1.27 1.27)) (justify left bottom) hide)
    )
    (property "Dielectric" "X5R" (at 171.958 44.45 0)
      (effects (font (size 1.27 1.27)) (justify left bottom) hide)
    )
    (pin "1")
    (pin "2")
    (instances
      (project "data-center-rdimm-ddr4-tester"
        (path ""
          (reference "C232") (unit 1)
        )
      )
    )
  )

  (symbol (lib_id "antmicroResistors0402:R_0R_0402") (at 363.22 55.245 0) (unit 1)
    (in_bom no) (on_board yes) (dnp yes)
    (property "Reference" "R197" (at 365.76 50.8 0)
      (effects (font (size 1.524 1.524)))
    )
    (property "Value" "R_0R_0402" (at 383.54 67.945 0)
      (effects (font (size 1.27 1.27) (thickness 0.15)) (justify left bottom) hide)
    )
    (property "Footprint" "antmicro-footprints:R_0402_1005Metric" (at 383.54 70.485 0)
      (effects (font (size 1.27 1.27) (thickness 0.15)) (justify left bottom) hide)
    )
    (property "Datasheet" "https://industrial.panasonic.com/cdbs/www-data/pdf/RDA0000/AOA0000C301.pdf" (at 383.54 73.025 0)
      (effects (font (size 1.27 1.27) (thickness 0.15)) (justify left bottom) hide)
    )
    (property "Manufacturer" "Panasonic" (at 383.54 78.105 0)
      (effects (font (size 1.27 1.27) (thickness 0.15)) (justify left bottom) hide)
    )
    (property "MPN" "ERJ2GE0R00X" (at 383.54 75.565 0)
      (effects (font (size 1.27 1.27) (thickness 0.15)) (justify left bottom) hide)
    )
    (property "Val" "0R" (at 365.76 53.34 0)
      (effects (font (size 1.27 1.27) (thickness 0.15)))
    )
    (property "License" "Apache-2.0" (at 383.54 80.645 0)
      (effects (font (size 1.27 1.27) (thickness 0.15)) (justify left bottom) hide)
    )
    (property "Author" "Antmicro" (at 383.54 83.185 0)
      (effects (font (size 1.27 1.27) (thickness 0.15)) (justify left bottom) hide)
    )
    (property "Tolerance" "~" (at 383.54 65.405 0)
      (effects (font (size 1.27 1.27)) (justify left bottom) hide)
    )
    (property "Current" "1A" (at 383.54 85.725 0)
      (effects (font (size 1.27 1.27) (thickness 0.15)) (justify left bottom) hide)
    )
    (property "DNP" "DNP" (at 365.76 55.245 0)
      (effects (font (size 1.27 1.27)))
    )
    (pin "1")
    (pin "2")
    (instances
      (project "data-center-rdimm-ddr4-tester"
        (path ""
          (reference "R197") (unit 1)
        )
      )
    )
  )

  (symbol (lib_id "antmicroResistorsmisc:R_0R01_1206") (at 381 187.325 0) (unit 1)
    (in_bom yes) (on_board yes) (dnp no)
    (property "Reference" "R202" (at 383.54 182.245 0)
      (effects (font (size 1.524 1.524)))
    )
    (property "Value" "R_0R01_1206" (at 401.32 200.025 0)
      (effects (font (size 1.27 1.27) (thickness 0.15)) (justify left bottom) hide)
    )
    (property "Footprint" "antmicro-footprints:R_1206_3216Metric" (at 401.32 202.565 0)
      (effects (font (size 1.27 1.27) (thickness 0.15)) (justify left bottom) hide)
    )
    (property "Datasheet" "https://www.yageo.com/upload/media/product/productsearch/datasheet/rchip/PYu-RL_Group_521_RoHS_L_2.pdf" (at 401.32 205.105 0)
      (effects (font (size 1.27 1.27) (thickness 0.15)) (justify left bottom) hide)
    )
    (property "Manufacturer" "Yaego" (at 401.32 210.185 0)
      (effects (font (size 1.27 1.27) (thickness 0.15)) (justify left bottom) hide)
    )
    (property "MPN" "RL1206FR-7W0R01L" (at 401.32 207.645 0)
      (effects (font (size 1.27 1.27) (thickness 0.15)) (justify left bottom) hide)
    )
    (property "Val" "0R01" (at 383.54 184.785 0)
      (effects (font (size 1.27 1.27) (thickness 0.15)))
    )
    (property "License" "Apache-2.0" (at 401.32 212.725 0)
      (effects (font (size 1.27 1.27) (thickness 0.15)) (justify left bottom) hide)
    )
    (property "Author" "Antmicro" (at 401.32 215.265 0)
      (effects (font (size 1.27 1.27) (thickness 0.15)) (justify left bottom) hide)
    )
    (property "Tolerance" "1%" (at 401.32 197.485 0)
      (effects (font (size 1.27 1.27)) (justify left bottom) hide)
    )
    (pin "1")
    (pin "2")
    (instances
      (project "data-center-rdimm-ddr4-tester"
        (path ""
          (reference "R202") (unit 1)
        )
      )
    )
  )

  (symbol (lib_id "antmicroLogicBuffersDriversReceiversTransceivers:74LVC2G07_SOT457") (at 139.7 250.825 0) (unit 1)
    (in_bom yes) (on_board yes) (dnp no) (fields_autoplaced)
    (property "Reference" "U24" (at 147.955 243.205 0)
      (effects (font (size 1.27 1.27)))
    )
    (property "Value" "74LVC2G07_SOT457" (at 168.91 257.175 0)
      (effects (font (size 1.27 1.27) (thickness 0.15)) (justify left bottom) hide)
    )
    (property "Footprint" "antmicro-footprints:SC-74-6_1.5x2.9mm_P0.95mm" (at 168.91 259.715 0)
      (effects (font (size 1.27 1.27) (thickness 0.15)) (justify left bottom) hide)
    )
    (property "Datasheet" "https://www.tme.eu/Document/2ad9356043a4952b9021ef50162f8c34/74LVC2G07.pdf" (at 168.91 262.255 0)
      (effects (font (size 1.27 1.27) (thickness 0.15)) (justify left bottom) hide)
    )
    (property "Manufacturer" "Nexperia" (at 168.91 264.795 0)
      (effects (font (size 1.27 1.27) (thickness 0.15)) (justify left bottom) hide)
    )
    (property "MPN" "74LVC2G07GV,125" (at 147.955 245.745 0)
      (effects (font (size 1.27 1.27) (thickness 0.15)))
    )
    (property "Author" "Antmicro" (at 168.91 269.875 0)
      (effects (font (size 1.27 1.27) (thickness 0.15)) (justify left bottom) hide)
    )
    (property "License" "Apache-2.0" (at 168.91 272.415 0)
      (effects (font (size 1.27 1.27) (thickness 0.15)) (justify left bottom) hide)
    )
    (pin "1")
    (pin "2")
    (pin "3")
    (pin "4")
    (pin "5")
    (pin "6")
    (instances
      (project "data-center-rdimm-ddr4-tester"
        (path ""
          (reference "U24") (unit 1)
        )
      )
    )
  )

  (symbol (lib_id "antmicropower:GND") (at 314.96 207.645 0) (unit 1)
    (in_bom yes) (on_board yes) (dnp no) (fields_autoplaced)
    (property "Reference" "#PWR0340" (at 314.96 213.995 0)
      (effects (font (size 1.27 1.27)) hide)
    )
    (property "Value" "GND" (at 314.96 212.725 0)
      (effects (font (size 1.27 1.27)))
    )
    (property "Footprint" "" (at 314.96 207.645 0)
      (effects (font (size 1.27 1.27)) hide)
    )
    (property "Datasheet" "" (at 314.96 207.645 0)
      (effects (font (size 1.27 1.27)) hide)
    )
    (property "Author" "Antmicro" (at 323.85 215.265 0)
      (effects (font (size 1.27 1.27) (thickness 0.15)) (justify left bottom) hide)
    )
    (property "License" "Apache-2.0" (at 323.85 217.805 0)
      (effects (font (size 1.27 1.27) (thickness 0.15)) (justify left bottom) hide)
    )
    (pin "1")
    (instances
      (project "data-center-rdimm-ddr4-tester"
        (path ""
          (reference "#PWR0340") (unit 1)
        )
      )
    )
  )

  (symbol (lib_id "antmicropower:GND") (at 50.165 255.27 0) (unit 1)
    (in_bom yes) (on_board yes) (dnp no) (fields_autoplaced)
    (property "Reference" "#PWR0405" (at 50.165 261.62 0)
      (effects (font (size 1.27 1.27)) hide)
    )
    (property "Value" "GND" (at 50.165 260.35 0)
      (effects (font (size 1.27 1.27)))
    )
    (property "Footprint" "" (at 50.165 255.27 0)
      (effects (font (size 1.27 1.27)) hide)
    )
    (property "Datasheet" "" (at 50.165 255.27 0)
      (effects (font (size 1.27 1.27)) hide)
    )
    (property "Author" "Antmicro" (at 59.055 262.89 0)
      (effects (font (size 1.27 1.27) (thickness 0.15)) (justify left bottom) hide)
    )
    (property "License" "Apache-2.0" (at 59.055 265.43 0)
      (effects (font (size 1.27 1.27) (thickness 0.15)) (justify left bottom) hide)
    )
    (pin "1")
    (instances
      (project "data-center-rdimm-ddr4-tester"
        (path ""
          (reference "#PWR0405") (unit 1)
        )
      )
    )
  )

  (symbol (lib_id "antmicropower:GND") (at 319.405 207.645 0) (unit 1)
    (in_bom yes) (on_board yes) (dnp no) (fields_autoplaced)
    (property "Reference" "#PWR0332" (at 319.405 213.995 0)
      (effects (font (size 1.27 1.27)) hide)
    )
    (property "Value" "GND" (at 319.405 212.725 0)
      (effects (font (size 1.27 1.27)))
    )
    (property "Footprint" "" (at 319.405 207.645 0)
      (effects (font (size 1.27 1.27)) hide)
    )
    (property "Datasheet" "" (at 319.405 207.645 0)
      (effects (font (size 1.27 1.27)) hide)
    )
    (property "Author" "Antmicro" (at 328.295 215.265 0)
      (effects (font (size 1.27 1.27) (thickness 0.15)) (justify left bottom) hide)
    )
    (property "License" "Apache-2.0" (at 328.295 217.805 0)
      (effects (font (size 1.27 1.27) (thickness 0.15)) (justify left bottom) hide)
    )
    (pin "1")
    (instances
      (project "data-center-rdimm-ddr4-tester"
        (path ""
          (reference "#PWR0332") (unit 1)
        )
      )
    )
  )

  (symbol (lib_id "antmicroResistors0603:R_330R_0.25W_0603") (at 102.87 253.365 0) (unit 1)
    (in_bom yes) (on_board yes) (dnp no)
    (property "Reference" "R17" (at 100.965 252.095 0)
      (effects (font (size 1.524 1.524)))
    )
    (property "Value" "R_330R_0.25W_0603" (at 123.19 266.065 0)
      (effects (font (size 1.27 1.27) (thickness 0.15)) (justify left bottom) hide)
    )
    (property "Footprint" "antmicro-footprints:R_0603_1608Metric" (at 123.19 268.605 0)
      (effects (font (size 1.27 1.27) (thickness 0.15)) (justify left bottom) hide)
    )
    (property "Datasheet" "https://www.mouser.pl/datasheet/2/315/Panasonic_Resistors_Thick_Film_Anti_Sulf_Anti_Surg-1825099.pdf" (at 123.19 271.145 0)
      (effects (font (size 1.27 1.27) (thickness 0.15)) (justify left bottom) hide)
    )
    (property "Manufacturer" "Panasonic" (at 123.19 276.225 0)
      (effects (font (size 1.27 1.27) (thickness 0.15)) (justify left bottom) hide)
    )
    (property "MPN" "ERJ-UP3F3300V" (at 123.19 273.685 0)
      (effects (font (size 1.27 1.27) (thickness 0.15)) (justify left bottom) hide)
    )
    (property "Val" "330R" (at 110.49 252.095 0)
      (effects (font (size 1.27 1.27) (thickness 0.15)))
    )
    (property "License" "Apache-2.0" (at 123.19 278.765 0)
      (effects (font (size 1.27 1.27) (thickness 0.15)) (justify left bottom) hide)
    )
    (property "Author" "Antmicro" (at 123.19 281.305 0)
      (effects (font (size 1.27 1.27) (thickness 0.15)) (justify left bottom) hide)
    )
    (property "Tolerance" "1%" (at 123.19 263.525 0)
      (effects (font (size 1.27 1.27)) (justify left bottom) hide)
    )
    (pin "1")
    (pin "2")
    (instances
      (project "data-center-rdimm-ddr4-tester"
        (path ""
          (reference "R17") (unit 1)
        )
      )
    )
  )

  (symbol (lib_id "antmicropower:GND") (at 165.735 198.755 0) (unit 1)
    (in_bom yes) (on_board yes) (dnp no) (fields_autoplaced)
    (property "Reference" "#PWR0226" (at 165.735 205.105 0)
      (effects (font (size 1.27 1.27)) hide)
    )
    (property "Value" "GND" (at 165.735 203.835 0)
      (effects (font (size 1.27 1.27)))
    )
    (property "Footprint" "" (at 165.735 198.755 0)
      (effects (font (size 1.27 1.27)) hide)
    )
    (property "Datasheet" "" (at 165.735 198.755 0)
      (effects (font (size 1.27 1.27)) hide)
    )
    (property "Author" "Antmicro" (at 174.625 206.375 0)
      (effects (font (size 1.27 1.27) (thickness 0.15)) (justify left bottom) hide)
    )
    (property "License" "Apache-2.0" (at 174.625 208.915 0)
      (effects (font (size 1.27 1.27) (thickness 0.15)) (justify left bottom) hide)
    )
    (pin "1")
    (instances
      (project "data-center-rdimm-ddr4-tester"
        (path ""
          (reference "#PWR0226") (unit 1)
        )
      )
    )
  )

  (symbol (lib_id "antmicropower:GND") (at 219.583 29.21 0) (unit 1)
    (in_bom yes) (on_board yes) (dnp no) (fields_autoplaced)
    (property "Reference" "#PWR0335" (at 219.583 35.56 0)
      (effects (font (size 1.27 1.27)) hide)
    )
    (property "Value" "GND" (at 219.583 34.29 0)
      (effects (font (size 1.27 1.27)))
    )
    (property "Footprint" "" (at 219.583 29.21 0)
      (effects (font (size 1.27 1.27)) hide)
    )
    (property "Datasheet" "" (at 219.583 29.21 0)
      (effects (font (size 1.27 1.27)) hide)
    )
    (property "Author" "Antmicro" (at 228.473 36.83 0)
      (effects (font (size 1.27 1.27) (thickness 0.15)) (justify left bottom) hide)
    )
    (property "License" "Apache-2.0" (at 228.473 39.37 0)
      (effects (font (size 1.27 1.27) (thickness 0.15)) (justify left bottom) hide)
    )
    (pin "1")
    (instances
      (project "data-center-rdimm-ddr4-tester"
        (path ""
          (reference "#PWR0335") (unit 1)
        )
      )
    )
  )

  (symbol (lib_id "data-center-rdimm-ddr4-tester:Net-Tie_2") (at 379.095 169.545 90) (unit 1)
    (in_bom yes) (on_board yes) (dnp no) (fields_autoplaced)
    (property "Reference" "NT15" (at 377.825 169.545 0)
      (effects (font (size 1.27 1.27)) hide)
    )
    (property "Value" "Net-Tie_2" (at 381 167.6399 90)
      (effects (font (size 1.27 1.27) (thickness 0.15)) (justify right) hide)
    )
    (property "Footprint" "data-center-rdimm-ddr4-tester-footprints:NetTie-2_SMD_Pad0.127mm" (at 384.175 147.955 0)
      (effects (font (size 1.27 1.27) (thickness 0.15)) (justify left bottom) hide)
    )
    (property "Datasheet" "" (at 386.715 147.955 0)
      (effects (font (size 1.27 1.27) (thickness 0.15)) (justify left bottom) hide)
    )
    (property "MPN" "" (at 387.985 147.955 0)
      (effects (font (size 1.27 1.27)) (justify left) hide)
    )
    (property "Manufacturer" "" (at 390.525 147.955 0)
      (effects (font (size 1.27 1.27)) (justify left) hide)
    )
    (property "Author" "Antmicro" (at 394.335 147.955 0)
      (effects (font (size 1.27 1.27) (thickness 0.15)) (justify left bottom) hide)
    )
    (property "License" "Apache-2.0" (at 396.875 147.955 0)
      (effects (font (size 1.27 1.27) (thickness 0.15)) (justify left bottom) hide)
    )
    (pin "1")
    (pin "2")
    (instances
      (project "data-center-rdimm-ddr4-tester"
        (path ""
          (reference "NT15") (unit 1)
        )
      )
    )
  )

  (symbol (lib_id "antmicropower:GND") (at 289.56 58.42 0) (unit 1)
    (in_bom yes) (on_board yes) (dnp no) (fields_autoplaced)
    (property "Reference" "#PWR0403" (at 289.56 64.77 0)
      (effects (font (size 1.27 1.27)) hide)
    )
    (property "Value" "GND" (at 289.56 63.5 0)
      (effects (font (size 1.27 1.27)))
    )
    (property "Footprint" "" (at 289.56 58.42 0)
      (effects (font (size 1.27 1.27)) hide)
    )
    (property "Datasheet" "" (at 289.56 58.42 0)
      (effects (font (size 1.27 1.27)) hide)
    )
    (property "Author" "Antmicro" (at 298.45 66.04 0)
      (effects (font (size 1.27 1.27) (thickness 0.15)) (justify left bottom) hide)
    )
    (property "License" "Apache-2.0" (at 298.45 68.58 0)
      (effects (font (size 1.27 1.27) (thickness 0.15)) (justify left bottom) hide)
    )
    (pin "1")
    (instances
      (project "data-center-rdimm-ddr4-tester"
        (path ""
          (reference "#PWR0403") (unit 1)
        )
      )
    )
  )

  (symbol (lib_id "data-center-rdimm-ddr4-tester:Net-Tie_2") (at 387.985 169.545 90) (unit 1)
    (in_bom yes) (on_board yes) (dnp no) (fields_autoplaced)
    (property "Reference" "NT16" (at 386.715 169.545 0)
      (effects (font (size 1.27 1.27)) hide)
    )
    (property "Value" "Net-Tie_2" (at 389.89 167.6399 90)
      (effects (font (size 1.27 1.27) (thickness 0.15)) (justify right) hide)
    )
    (property "Footprint" "data-center-rdimm-ddr4-tester-footprints:NetTie-2_SMD_Pad0.127mm" (at 393.065 147.955 0)
      (effects (font (size 1.27 1.27) (thickness 0.15)) (justify left bottom) hide)
    )
    (property "Datasheet" "" (at 395.605 147.955 0)
      (effects (font (size 1.27 1.27) (thickness 0.15)) (justify left bottom) hide)
    )
    (property "MPN" "" (at 396.875 147.955 0)
      (effects (font (size 1.27 1.27)) (justify left) hide)
    )
    (property "Manufacturer" "" (at 399.415 147.955 0)
      (effects (font (size 1.27 1.27)) (justify left) hide)
    )
    (property "Author" "Antmicro" (at 403.225 147.955 0)
      (effects (font (size 1.27 1.27) (thickness 0.15)) (justify left bottom) hide)
    )
    (property "License" "Apache-2.0" (at 405.765 147.955 0)
      (effects (font (size 1.27 1.27) (thickness 0.15)) (justify left bottom) hide)
    )
    (pin "1")
    (pin "2")
    (instances
      (project "data-center-rdimm-ddr4-tester"
        (path ""
          (reference "NT16") (unit 1)
        )
      )
    )
  )

  (symbol (lib_id "antmicroPMICVoltageRegulatorsLinear:NCP718ASN500_SOT") (at 31.115 200.66 0) (unit 1)
    (in_bom yes) (on_board yes) (dnp no)
    (property "Reference" "U25" (at 38.735 193.675 0)
      (effects (font (size 1.27 1.27)))
    )
    (property "Value" "NCP718ASN500_SOT" (at 61.595 205.74 0)
      (effects (font (size 1.27 1.27) (thickness 0.15)) (justify left bottom) hide)
    )
    (property "Footprint" "antmicro-footprints:SOT-23-5" (at 61.595 208.28 0)
      (effects (font (size 1.27 1.27) (thickness 0.15)) (justify left bottom) hide)
    )
    (property "Datasheet" "https://www.mouser.pl/datasheet/2/308/NCP718_D-1224359.pdf" (at 61.595 210.82 0)
      (effects (font (size 1.27 1.27) (thickness 0.15)) (justify left bottom) hide)
    )
    (property "MPN" "NCP718ASN500T1G" (at 38.735 196.215 0)
      (effects (font (size 1.27 1.27) (thickness 0.15)))
    )
    (property "Manufacturer" "ON Semiconductor" (at 61.595 215.9 0)
      (effects (font (size 1.27 1.27) (thickness 0.15)) (justify left bottom) hide)
    )
    (property "Author" "Antmicro" (at 61.595 218.44 0)
      (effects (font (size 1.27 1.27) (thickness 0.15)) (justify left bottom) hide)
    )
    (property "License" "Apache-2.0" (at 61.595 220.98 0)
      (effects (font (size 1.27 1.27) (thickness 0.15)) (justify left bottom) hide)
    )
    (pin "1")
    (pin "2")
    (pin "3")
    (pin "4")
    (pin "5")
    (instances
      (project "data-center-rdimm-ddr4-tester"
        (path ""
          (reference "U25") (unit 1)
        )
      )
    )
  )

  (symbol (lib_id "antmicroResistors0402:R_10k_0402") (at 314.96 132.08 0) (unit 1)
    (in_bom yes) (on_board yes) (dnp no)
    (property "Reference" "R194" (at 317.5 133.985 0)
      (effects (font (size 1.524 1.524)))
    )
    (property "Value" "R_10k_0402" (at 335.28 144.78 0)
      (effects (font (size 1.27 1.27) (thickness 0.15)) (justify left bottom) hide)
    )
    (property "Footprint" "antmicro-footprints:R_0402_1005Metric" (at 335.28 147.32 0)
      (effects (font (size 1.27 1.27) (thickness 0.15)) (justify left bottom) hide)
    )
    (property "Datasheet" "https://www.bourns.com/docs/product-datasheets/cr.pdf" (at 335.28 149.86 0)
      (effects (font (size 1.27 1.27) (thickness 0.15)) (justify left bottom) hide)
    )
    (property "Manufacturer" "Bourns" (at 335.28 154.94 0)
      (effects (font (size 1.27 1.27) (thickness 0.15)) (justify left bottom) hide)
    )
    (property "MPN" "CR0402-FX-1002GLF" (at 335.28 152.4 0)
      (effects (font (size 1.27 1.27) (thickness 0.15)) (justify left bottom) hide)
    )
    (property "Val" "10k" (at 317.5 135.89 0)
      (effects (font (size 1.27 1.27) (thickness 0.15)))
    )
    (property "License" "Apache-2.0" (at 335.28 157.48 0)
      (effects (font (size 1.27 1.27) (thickness 0.15)) (justify left bottom) hide)
    )
    (property "Author" "Antmicro" (at 335.28 160.02 0)
      (effects (font (size 1.27 1.27) (thickness 0.15)) (justify left bottom) hide)
    )
    (property "Tolerance" "1%" (at 335.28 142.24 0)
      (effects (font (size 1.27 1.27)) (justify left bottom) hide)
    )
    (pin "1")
    (pin "2")
    (instances
      (project "data-center-rdimm-ddr4-tester"
        (path ""
          (reference "R194") (unit 1)
        )
      )
    )
  )

  (symbol (lib_id "antmicroResistorsmisc:R_0R01_1206") (at 381 206.375 0) (unit 1)
    (in_bom yes) (on_board yes) (dnp no)
    (property "Reference" "R204" (at 383.54 201.295 0)
      (effects (font (size 1.524 1.524)))
    )
    (property "Value" "R_0R01_1206" (at 401.32 219.075 0)
      (effects (font (size 1.27 1.27) (thickness 0.15)) (justify left bottom) hide)
    )
    (property "Footprint" "antmicro-footprints:R_1206_3216Metric" (at 401.32 221.615 0)
      (effects (font (size 1.27 1.27) (thickness 0.15)) (justify left bottom) hide)
    )
    (property "Datasheet" "https://www.yageo.com/upload/media/product/productsearch/datasheet/rchip/PYu-RL_Group_521_RoHS_L_2.pdf" (at 401.32 224.155 0)
      (effects (font (size 1.27 1.27) (thickness 0.15)) (justify left bottom) hide)
    )
    (property "Manufacturer" "Yaego" (at 401.32 229.235 0)
      (effects (font (size 1.27 1.27) (thickness 0.15)) (justify left bottom) hide)
    )
    (property "MPN" "RL1206FR-7W0R01L" (at 401.32 226.695 0)
      (effects (font (size 1.27 1.27) (thickness 0.15)) (justify left bottom) hide)
    )
    (property "Val" "0R01" (at 383.54 203.835 0)
      (effects (font (size 1.27 1.27) (thickness 0.15)))
    )
    (property "License" "Apache-2.0" (at 401.32 231.775 0)
      (effects (font (size 1.27 1.27) (thickness 0.15)) (justify left bottom) hide)
    )
    (property "Author" "Antmicro" (at 401.32 234.315 0)
      (effects (font (size 1.27 1.27) (thickness 0.15)) (justify left bottom) hide)
    )
    (property "Tolerance" "1%" (at 401.32 216.535 0)
      (effects (font (size 1.27 1.27)) (justify left bottom) hide)
    )
    (pin "1")
    (pin "2")
    (instances
      (project "data-center-rdimm-ddr4-tester"
        (path ""
          (reference "R204") (unit 1)
        )
      )
    )
  )

  (symbol (lib_id "antmicroResistors0402:R_10k_0402") (at 394.97 80.01 270) (unit 1)
    (in_bom yes) (on_board yes) (dnp no) (fields_autoplaced)
    (property "Reference" "R217" (at 397.129 81.28 90)
      (effects (font (size 1.524 1.524)) (justify left))
    )
    (property "Value" "R_10k_0402" (at 382.27 100.33 0)
      (effects (font (size 1.27 1.27) (thickness 0.15)) (justify left bottom) hide)
    )
    (property "Footprint" "antmicro-footprints:R_0402_1005Metric" (at 379.73 100.33 0)
      (effects (font (size 1.27 1.27) (thickness 0.15)) (justify left bottom) hide)
    )
    (property "Datasheet" "https://www.bourns.com/docs/product-datasheets/cr.pdf" (at 377.19 100.33 0)
      (effects (font (size 1.27 1.27) (thickness 0.15)) (justify left bottom) hide)
    )
    (property "Manufacturer" "Bourns" (at 372.11 100.33 0)
      (effects (font (size 1.27 1.27) (thickness 0.15)) (justify left bottom) hide)
    )
    (property "MPN" "CR0402-FX-1002GLF" (at 374.65 100.33 0)
      (effects (font (size 1.27 1.27) (thickness 0.15)) (justify left bottom) hide)
    )
    (property "Val" "10k" (at 397.129 84.4549 90)
      (effects (font (size 1.27 1.27) (thickness 0.15)) (justify left))
    )
    (property "License" "Apache-2.0" (at 369.57 100.33 0)
      (effects (font (size 1.27 1.27) (thickness 0.15)) (justify left bottom) hide)
    )
    (property "Author" "Antmicro" (at 367.03 100.33 0)
      (effects (font (size 1.27 1.27) (thickness 0.15)) (justify left bottom) hide)
    )
    (property "Tolerance" "1%" (at 384.81 100.33 0)
      (effects (font (size 1.27 1.27)) (justify left bottom) hide)
    )
    (pin "1")
    (pin "2")
    (instances
      (project "data-center-rdimm-ddr4-tester"
        (path ""
          (reference "R217") (unit 1)
        )
      )
    )
  )

  (symbol (lib_id "antmicropower:GND") (at 368.3 42.545 0) (unit 1)
    (in_bom yes) (on_board yes) (dnp no) (fields_autoplaced)
    (property "Reference" "#PWR0355" (at 368.3 48.895 0)
      (effects (font (size 1.27 1.27)) hide)
    )
    (property "Value" "GND" (at 368.3 47.625 0)
      (effects (font (size 1.27 1.27)))
    )
    (property "Footprint" "" (at 368.3 42.545 0)
      (effects (font (size 1.27 1.27)) hide)
    )
    (property "Datasheet" "" (at 368.3 42.545 0)
      (effects (font (size 1.27 1.27)) hide)
    )
    (property "Author" "Antmicro" (at 377.19 50.165 0)
      (effects (font (size 1.27 1.27) (thickness 0.15)) (justify left bottom) hide)
    )
    (property "License" "Apache-2.0" (at 377.19 52.705 0)
      (effects (font (size 1.27 1.27) (thickness 0.15)) (justify left bottom) hide)
    )
    (pin "1")
    (instances
      (project "data-center-rdimm-ddr4-tester"
        (path ""
          (reference "#PWR0355") (unit 1)
        )
      )
    )
  )

  (symbol (lib_id "antmicroTestPoints:TP_1mm_SMD") (at 156.845 233.68 180) (unit 1)
    (in_bom yes) (on_board yes) (dnp no) (fields_autoplaced)
    (property "Reference" "TP14" (at 151.765 233.6801 0)
      (effects (font (size 1.27 1.27)) (justify left))
    )
    (property "Value" "TP_1mm_SMD" (at 141.605 226.06 0)
      (effects (font (size 1.27 1.27) (thickness 0.15)) (justify left bottom) hide)
    )
    (property "Footprint" "antmicro-footprints:TP_SMD_1mm" (at 141.605 223.52 0)
      (effects (font (size 1.27 1.27) (thickness 0.15)) (justify left bottom) hide)
    )
    (property "Datasheet" "" (at 141.605 220.98 0)
      (effects (font (size 1.27 1.27) (thickness 0.15)) (justify left bottom) hide)
    )
    (property "MPN" "" (at 156.845 233.68 0)
      (effects (font (size 1.27 1.27)) hide)
    )
    (property "Manufacturer" "" (at 156.845 233.68 0)
      (effects (font (size 1.27 1.27)) hide)
    )
    (property "Author" "Antmicro" (at 141.605 218.44 0)
      (effects (font (size 1.27 1.27) (thickness 0.15)) (justify left bottom) hide)
    )
    (property "License" "Apache-2.0" (at 141.605 215.9 0)
      (effects (font (size 1.27 1.27) (thickness 0.15)) (justify left bottom) hide)
    )
    (pin "1")
    (instances
      (project "data-center-rdimm-ddr4-tester"
        (path ""
          (reference "TP14") (unit 1)
        )
      )
    )
  )

  (symbol (lib_id "antmicroCapacitors0402:C_10u_0402") (at 163.83 47.625 270) (unit 1)
    (in_bom yes) (on_board yes) (dnp no) (fields_autoplaced)
    (property "Reference" "C33" (at 166.37 48.9013 90)
      (effects (font (size 1.524 1.524)) (justify left))
    )
    (property "Value" "C_10u_0402" (at 153.67 67.945 0)
      (effects (font (size 1.27 1.27) (thickness 0.15)) (justify left bottom) hide)
    )
    (property "Footprint" "antmicro-footprints:C_0402_1005Metric" (at 151.13 67.945 0)
      (effects (font (size 1.27 1.27) (thickness 0.15)) (justify left bottom) hide)
    )
    (property "Datasheet" " " (at 148.59 67.945 0)
      (effects (font (size 1.27 1.27) (thickness 0.15)) (justify left bottom) hide)
    )
    (property "Manufacturer" "Yaego" (at 143.51 67.945 0)
      (effects (font (size 1.27 1.27) (thickness 0.15)) (justify left bottom) hide)
    )
    (property "MPN" "CC0402MRX5R5BB106" (at 146.05 67.945 0)
      (effects (font (size 1.27 1.27) (thickness 0.15)) (justify left bottom) hide)
    )
    (property "Val" "10u" (at 166.37 52.0762 90)
      (effects (font (size 1.27 1.27) (thickness 0.15)) (justify left))
    )
    (property "License" "Apache-2.0" (at 140.97 67.945 0)
      (effects (font (size 1.27 1.27) (thickness 0.15)) (justify left bottom) hide)
    )
    (property "Author" "Antmicro" (at 138.43 67.945 0)
      (effects (font (size 1.27 1.27) (thickness 0.15)) (justify left bottom) hide)
    )
    (property "Voltage" "" (at 135.89 67.945 0)
      (effects (font (size 1.27 1.27)) (justify left bottom) hide)
    )
    (property "Dielectric" "" (at 133.35 67.945 0)
      (effects (font (size 1.27 1.27)) (justify left bottom) hide)
    )
    (pin "1")
    (pin "2")
    (instances
      (project "data-center-rdimm-ddr4-tester"
        (path ""
          (reference "C33") (unit 1)
        )
      )
    )
  )

  (symbol (lib_id "antmicroCapacitors0402:C_1u_0402") (at 52.705 201.93 270) (unit 1)
    (in_bom yes) (on_board yes) (dnp no) (fields_autoplaced)
    (property "Reference" "C281" (at 55.245 203.2063 90)
      (effects (font (size 1.524 1.524)) (justify left))
    )
    (property "Value" "C_1u_0402" (at 42.545 222.25 0)
      (effects (font (size 1.27 1.27) (thickness 0.15)) (justify left bottom) hide)
    )
    (property "Footprint" "antmicro-footprints:C_0402_1005Metric" (at 40.005 222.25 0)
      (effects (font (size 1.27 1.27) (thickness 0.15)) (justify left bottom) hide)
    )
    (property "Datasheet" " " (at 37.465 222.25 0)
      (effects (font (size 1.27 1.27) (thickness 0.15)) (justify left bottom) hide)
    )
    (property "Manufacturer" "TDK" (at 32.385 222.25 0)
      (effects (font (size 1.27 1.27) (thickness 0.15)) (justify left bottom) hide)
    )
    (property "MPN" "C1005X6S1A105K050BC" (at 34.925 222.25 0)
      (effects (font (size 1.27 1.27) (thickness 0.15)) (justify left bottom) hide)
    )
    (property "Val" "1u" (at 55.245 206.3812 90)
      (effects (font (size 1.27 1.27) (thickness 0.15)) (justify left))
    )
    (property "License" "Apache-2.0" (at 29.845 222.25 0)
      (effects (font (size 1.27 1.27) (thickness 0.15)) (justify left bottom) hide)
    )
    (property "Author" "Antmicro" (at 27.305 222.25 0)
      (effects (font (size 1.27 1.27) (thickness 0.15)) (justify left bottom) hide)
    )
    (property "Voltage" "" (at 24.765 222.25 0)
      (effects (font (size 1.27 1.27)) (justify left bottom) hide)
    )
    (property "Dielectric" "" (at 22.225 222.25 0)
      (effects (font (size 1.27 1.27)) (justify left bottom) hide)
    )
    (pin "1")
    (pin "2")
    (instances
      (project "data-center-rdimm-ddr4-tester"
        (path ""
          (reference "C281") (unit 1)
        )
      )
    )
  )

  (symbol (lib_id "antmicroCapacitors0402:C_100n_0402") (at 50.165 250.19 270) (unit 1)
    (in_bom yes) (on_board yes) (dnp no) (fields_autoplaced)
    (property "Reference" "C285" (at 53.34 251.4663 90)
      (effects (font (size 1.524 1.524)) (justify left))
    )
    (property "Value" "C_100n_0402" (at 40.005 270.51 0)
      (effects (font (size 1.27 1.27) (thickness 0.15)) (justify left bottom) hide)
    )
    (property "Footprint" "antmicro-footprints:C_0402_1005Metric" (at 37.465 270.51 0)
      (effects (font (size 1.27 1.27) (thickness 0.15)) (justify left bottom) hide)
    )
    (property "Datasheet" "https://search.murata.co.jp/Ceramy/image/img/A01X/G101/ENG/GRM155R61H104KE14-01.pdf" (at 34.925 270.51 0)
      (effects (font (size 1.27 1.27) (thickness 0.15)) (justify left bottom) hide)
    )
    (property "Manufacturer" "Murata" (at 29.845 270.51 0)
      (effects (font (size 1.27 1.27) (thickness 0.15)) (justify left bottom) hide)
    )
    (property "MPN" "GRM155R61H104KE14D" (at 32.385 270.51 0)
      (effects (font (size 1.27 1.27) (thickness 0.15)) (justify left bottom) hide)
    )
    (property "Val" "100n" (at 53.34 254.6412 90)
      (effects (font (size 1.27 1.27) (thickness 0.15)) (justify left))
    )
    (property "License" "Apache-2.0" (at 27.305 270.51 0)
      (effects (font (size 1.27 1.27) (thickness 0.15)) (justify left bottom) hide)
    )
    (property "Author" "Antmicro" (at 24.765 270.51 0)
      (effects (font (size 1.27 1.27) (thickness 0.15)) (justify left bottom) hide)
    )
    (property "Voltage" "50V" (at 22.225 270.51 0)
      (effects (font (size 1.27 1.27)) (justify left bottom) hide)
    )
    (property "Dielectric" "X5R" (at 19.685 270.51 0)
      (effects (font (size 1.27 1.27)) (justify left bottom) hide)
    )
    (pin "1")
    (pin "2")
    (instances
      (project "data-center-rdimm-ddr4-tester"
        (path ""
          (reference "C285") (unit 1)
        )
      )
    )
  )

  (symbol (lib_id "antmicropower:GND") (at 389.89 85.09 0) (unit 1)
    (in_bom yes) (on_board yes) (dnp no) (fields_autoplaced)
    (property "Reference" "#PWR0354" (at 389.89 91.44 0)
      (effects (font (size 1.27 1.27)) hide)
    )
    (property "Value" "GND" (at 389.89 89.789 0)
      (effects (font (size 1.27 1.27)))
    )
    (property "Footprint" "" (at 389.89 85.09 0)
      (effects (font (size 1.27 1.27)) hide)
    )
    (property "Datasheet" "" (at 389.89 85.09 0)
      (effects (font (size 1.27 1.27)) hide)
    )
    (property "Author" "Antmicro" (at 398.78 92.71 0)
      (effects (font (size 1.27 1.27) (thickness 0.15)) (justify left bottom) hide)
    )
    (property "License" "Apache-2.0" (at 398.78 95.25 0)
      (effects (font (size 1.27 1.27) (thickness 0.15)) (justify left bottom) hide)
    )
    (pin "1")
    (instances
      (project "data-center-rdimm-ddr4-tester"
        (path ""
          (reference "#PWR0354") (unit 1)
        )
      )
    )
  )

  (symbol (lib_id "antmicroResistors0402:R_100k_0402") (at 156.21 193.675 270) (unit 1)
    (in_bom yes) (on_board yes) (dnp no) (fields_autoplaced)
    (property "Reference" "R121" (at 154.305 194.945 90)
      (effects (font (size 1.524 1.524)) (justify right))
    )
    (property "Value" "R_100k_0402" (at 143.51 213.995 0)
      (effects (font (size 1.27 1.27) (thickness 0.15)) (justify left bottom) hide)
    )
    (property "Footprint" "antmicro-footprints:R_0402_1005Metric" (at 140.97 213.995 0)
      (effects (font (size 1.27 1.27) (thickness 0.15)) (justify left bottom) hide)
    )
    (property "Datasheet" "https://www.bourns.com/docs/product-datasheets/cr.pdf" (at 138.43 213.995 0)
      (effects (font (size 1.27 1.27) (thickness 0.15)) (justify left bottom) hide)
    )
    (property "Manufacturer" "Bourns" (at 133.35 213.995 0)
      (effects (font (size 1.27 1.27) (thickness 0.15)) (justify left bottom) hide)
    )
    (property "MPN" "CR0402-FX-1003GLF" (at 135.89 213.995 0)
      (effects (font (size 1.27 1.27) (thickness 0.15)) (justify left bottom) hide)
    )
    (property "Val" "100k" (at 154.305 198.1199 90)
      (effects (font (size 1.27 1.27) (thickness 0.15)) (justify right))
    )
    (property "License" "Apache-2.0" (at 130.81 213.995 0)
      (effects (font (size 1.27 1.27) (thickness 0.15)) (justify left bottom) hide)
    )
    (property "Author" "Antmicro" (at 128.27 213.995 0)
      (effects (font (size 1.27 1.27) (thickness 0.15)) (justify left bottom) hide)
    )
    (property "Tolerance" "1%" (at 146.05 213.995 0)
      (effects (font (size 1.27 1.27)) (justify left bottom) hide)
    )
    (pin "1")
    (pin "2")
    (instances
      (project "data-center-rdimm-ddr4-tester"
        (path ""
          (reference "R121") (unit 1)
        )
      )
    )
  )

  (symbol (lib_id "antmicroResistors0402:R_10k_0402") (at 243.205 91.44 270) (unit 1)
    (in_bom yes) (on_board yes) (dnp no) (fields_autoplaced)
    (property "Reference" "R213" (at 245.11 92.71 90)
      (effects (font (size 1.524 1.524)) (justify left))
    )
    (property "Value" "R_10k_0402" (at 230.505 111.76 0)
      (effects (font (size 1.27 1.27) (thickness 0.15)) (justify left bottom) hide)
    )
    (property "Footprint" "antmicro-footprints:R_0402_1005Metric" (at 227.965 111.76 0)
      (effects (font (size 1.27 1.27) (thickness 0.15)) (justify left bottom) hide)
    )
    (property "Datasheet" "https://www.bourns.com/docs/product-datasheets/cr.pdf" (at 225.425 111.76 0)
      (effects (font (size 1.27 1.27) (thickness 0.15)) (justify left bottom) hide)
    )
    (property "Manufacturer" "Bourns" (at 220.345 111.76 0)
      (effects (font (size 1.27 1.27) (thickness 0.15)) (justify left bottom) hide)
    )
    (property "MPN" "CR0402-FX-1002GLF" (at 222.885 111.76 0)
      (effects (font (size 1.27 1.27) (thickness 0.15)) (justify left bottom) hide)
    )
    (property "Val" "10k" (at 245.11 95.8849 90)
      (effects (font (size 1.27 1.27) (thickness 0.15)) (justify left))
    )
    (property "License" "Apache-2.0" (at 217.805 111.76 0)
      (effects (font (size 1.27 1.27) (thickness 0.15)) (justify left bottom) hide)
    )
    (property "Author" "Antmicro" (at 215.265 111.76 0)
      (effects (font (size 1.27 1.27) (thickness 0.15)) (justify left bottom) hide)
    )
    (property "Tolerance" "1%" (at 233.045 111.76 0)
      (effects (font (size 1.27 1.27)) (justify left bottom) hide)
    )
    (pin "1")
    (pin "2")
    (instances
      (project "data-center-rdimm-ddr4-tester"
        (path ""
          (reference "R213") (unit 1)
        )
      )
    )
  )

  (symbol (lib_id "antmicroCapacitors0402:C_100n_0402") (at 112.395 221.615 270) (unit 1)
    (in_bom yes) (on_board yes) (dnp no) (fields_autoplaced)
    (property "Reference" "C282" (at 109.855 222.8913 90)
      (effects (font (size 1.524 1.524)) (justify right))
    )
    (property "Value" "C_100n_0402" (at 102.235 241.935 0)
      (effects (font (size 1.27 1.27) (thickness 0.15)) (justify left bottom) hide)
    )
    (property "Footprint" "antmicro-footprints:C_0402_1005Metric" (at 99.695 241.935 0)
      (effects (font (size 1.27 1.27) (thickness 0.15)) (justify left bottom) hide)
    )
    (property "Datasheet" "https://search.murata.co.jp/Ceramy/image/img/A01X/G101/ENG/GRM155R61H104KE14-01.pdf" (at 97.155 241.935 0)
      (effects (font (size 1.27 1.27) (thickness 0.15)) (justify left bottom) hide)
    )
    (property "Manufacturer" "Murata" (at 92.075 241.935 0)
      (effects (font (size 1.27 1.27) (thickness 0.15)) (justify left bottom) hide)
    )
    (property "MPN" "GRM155R61H104KE14D" (at 94.615 241.935 0)
      (effects (font (size 1.27 1.27) (thickness 0.15)) (justify left bottom) hide)
    )
    (property "Val" "100n" (at 109.855 226.0662 90)
      (effects (font (size 1.27 1.27) (thickness 0.15)) (justify right))
    )
    (property "License" "Apache-2.0" (at 89.535 241.935 0)
      (effects (font (size 1.27 1.27) (thickness 0.15)) (justify left bottom) hide)
    )
    (property "Author" "Antmicro" (at 86.995 241.935 0)
      (effects (font (size 1.27 1.27) (thickness 0.15)) (justify left bottom) hide)
    )
    (property "Voltage" "50V" (at 84.455 241.935 0)
      (effects (font (size 1.27 1.27)) (justify left bottom) hide)
    )
    (property "Dielectric" "X5R" (at 81.915 241.935 0)
      (effects (font (size 1.27 1.27)) (justify left bottom) hide)
    )
    (pin "1")
    (pin "2")
    (instances
      (project "data-center-rdimm-ddr4-tester"
        (path ""
          (reference "C282") (unit 1)
        )
      )
    )
  )

  (symbol (lib_id "antmicroPushbuttonSwitches:SW_1-1825027-1_THT") (at 143.51 223.52 0) (mirror y) (unit 1)
    (in_bom yes) (on_board yes) (dnp no)
    (property "Reference" "S3" (at 138.43 218.44 0)
      (effects (font (size 1.524 1.524)))
    )
    (property "Value" "SW_1-1825027-1" (at 138.43 229.87 0)
      (effects (font (size 1.27 1.27) (thickness 0.15)) hide)
    )
    (property "Footprint" "antmicro-footprints:SW_1-1825027-1_THT" (at 118.11 233.68 0)
      (effects (font (size 1.27 1.27) (thickness 0.15)) (justify left bottom) hide)
    )
    (property "Datasheet" "https://www.te.com/commerce/DocumentDelivery/DDEController?Action=showdoc&DocId=Customer+Drawing%7F1825027%7FH1%7Fpdf%7FEnglish%7FENG_CD_1825027_H1.pdf%7F1-1825027-1" (at 118.11 236.22 0)
      (effects (font (size 1.27 1.27) (thickness 0.15)) (justify left bottom) hide)
    )
    (property "MPN" "1-1825027-1" (at 147.32 228.6 0)
      (effects (font (size 1.27 1.27) (thickness 0.15)) (justify left bottom))
    )
    (property "Manufacturer" "TE Connectivity" (at 118.11 241.3 0)
      (effects (font (size 1.27 1.27) (thickness 0.15)) (justify left bottom) hide)
    )
    (property "Author" "Antmicro" (at 118.11 243.84 0)
      (effects (font (size 1.27 1.27) (thickness 0.15)) (justify left bottom) hide)
    )
    (property "License" "Apache-2.0" (at 118.11 246.38 0)
      (effects (font (size 1.27 1.27) (thickness 0.15)) (justify left bottom) hide)
    )
    (pin "1")
    (pin "2")
    (pin "SH")
    (instances
      (project "data-center-rdimm-ddr4-tester"
        (path ""
          (reference "S3") (unit 1)
        )
      )
    )
  )

  (symbol (lib_id "antmicropower:GND") (at 89.535 197.485 0) (unit 1)
    (in_bom yes) (on_board yes) (dnp no) (fields_autoplaced)
    (property "Reference" "#PWR0365" (at 89.535 203.835 0)
      (effects (font (size 1.27 1.27)) hide)
    )
    (property "Value" "GND" (at 87.63 198.7549 0)
      (effects (font (size 1.27 1.27)) (justify right))
    )
    (property "Footprint" "" (at 89.535 197.485 0)
      (effects (font (size 1.27 1.27)) hide)
    )
    (property "Datasheet" "" (at 89.535 197.485 0)
      (effects (font (size 1.27 1.27)) hide)
    )
    (property "Author" "Antmicro" (at 98.425 205.105 0)
      (effects (font (size 1.27 1.27) (thickness 0.15)) (justify left bottom) hide)
    )
    (property "License" "Apache-2.0" (at 98.425 207.645 0)
      (effects (font (size 1.27 1.27) (thickness 0.15)) (justify left bottom) hide)
    )
    (pin "1")
    (instances
      (project "data-center-rdimm-ddr4-tester"
        (path ""
          (reference "#PWR0365") (unit 1)
        )
      )
    )
  )

  (symbol (lib_id "antmicroResistorsmisc:R_0R01_1206") (at 381 127.635 0) (unit 1)
    (in_bom yes) (on_board yes) (dnp no)
    (property "Reference" "R198" (at 383.54 122.555 0)
      (effects (font (size 1.524 1.524)))
    )
    (property "Value" "R_0R01_1206" (at 401.32 140.335 0)
      (effects (font (size 1.27 1.27) (thickness 0.15)) (justify left bottom) hide)
    )
    (property "Footprint" "antmicro-footprints:R_1206_3216Metric" (at 401.32 142.875 0)
      (effects (font (size 1.27 1.27) (thickness 0.15)) (justify left bottom) hide)
    )
    (property "Datasheet" "https://www.yageo.com/upload/media/product/productsearch/datasheet/rchip/PYu-RL_Group_521_RoHS_L_2.pdf" (at 401.32 145.415 0)
      (effects (font (size 1.27 1.27) (thickness 0.15)) (justify left bottom) hide)
    )
    (property "Manufacturer" "Yaego" (at 401.32 150.495 0)
      (effects (font (size 1.27 1.27) (thickness 0.15)) (justify left bottom) hide)
    )
    (property "MPN" "RL1206FR-7W0R01L" (at 401.32 147.955 0)
      (effects (font (size 1.27 1.27) (thickness 0.15)) (justify left bottom) hide)
    )
    (property "Val" "0R01" (at 383.54 125.095 0)
      (effects (font (size 1.27 1.27) (thickness 0.15)))
    )
    (property "License" "Apache-2.0" (at 401.32 153.035 0)
      (effects (font (size 1.27 1.27) (thickness 0.15)) (justify left bottom) hide)
    )
    (property "Author" "Antmicro" (at 401.32 155.575 0)
      (effects (font (size 1.27 1.27) (thickness 0.15)) (justify left bottom) hide)
    )
    (property "Tolerance" "1%" (at 401.32 137.795 0)
      (effects (font (size 1.27 1.27)) (justify left bottom) hide)
    )
    (pin "1")
    (pin "2")
    (instances
      (project "data-center-rdimm-ddr4-tester"
        (path ""
          (reference "R198") (unit 1)
        )
      )
    )
  )

  (symbol (lib_id "data-center-rdimm-ddr4-tester:TestPoint_Probe_1206_RCW-0C") (at 323.85 97.79 0) (mirror x) (unit 1)
    (in_bom yes) (on_board yes) (dnp no)
    (property "Reference" "GND1" (at 332.105 96.52 0)
      (effects (font (size 1.27 1.27)))
    )
    (property "Value" "TestPoint_Probe_1206_RCW-0C" (at 326.898 93.98 0)
      (effects (font (size 1.27 1.27) (thickness 0.15)) hide)
    )
    (property "Footprint" "data-center-rdimm-ddr4-tester-footprints:PROBE_PAD_1206" (at 341.63 87.63 0)
      (effects (font (size 1.27 1.27) (thickness 0.15)) (justify left bottom) hide)
    )
    (property "Datasheet" "https://www.te.com/commerce/DocumentDelivery/DDEController?Action=srchrtrv&DocNm=1773266&DocType=DS&DocLang=English" (at 341.63 85.09 0)
      (effects (font (size 1.27 1.27) (thickness 0.15)) (justify left bottom) hide)
    )
    (property "MPN" "RCW-0C" (at 332.105 99.06 0)
      (effects (font (size 1.27 1.27) (thickness 0.15)))
    )
    (property "Manufacturer" "TE Connectivity" (at 341.63 80.01 0)
      (effects (font (size 1.27 1.27) (thickness 0.15)) (justify left bottom) hide)
    )
    (property "Author" "Antmicro" (at 341.63 77.47 0)
      (effects (font (size 1.27 1.27) (thickness 0.15)) (justify left bottom) hide)
    )
    (property "License" "Apache-2.0" (at 341.63 74.93 0)
      (effects (font (size 1.27 1.27) (thickness 0.15)) (justify left bottom) hide)
    )
    (pin "1")
    (instances
      (project "data-center-rdimm-ddr4-tester"
        (path ""
          (reference "GND1") (unit 1)
        )
      )
    )
  )

  (symbol (lib_id "antmicroResistorsmisc:R_0R01_1206") (at 381 146.685 0) (unit 1)
    (in_bom yes) (on_board yes) (dnp no)
    (property "Reference" "R200" (at 383.54 141.605 0)
      (effects (font (size 1.524 1.524)))
    )
    (property "Value" "R_0R01_1206" (at 401.32 159.385 0)
      (effects (font (size 1.27 1.27) (thickness 0.15)) (justify left bottom) hide)
    )
    (property "Footprint" "antmicro-footprints:R_1206_3216Metric" (at 401.32 161.925 0)
      (effects (font (size 1.27 1.27) (thickness 0.15)) (justify left bottom) hide)
    )
    (property "Datasheet" "https://www.yageo.com/upload/media/product/productsearch/datasheet/rchip/PYu-RL_Group_521_RoHS_L_2.pdf" (at 401.32 164.465 0)
      (effects (font (size 1.27 1.27) (thickness 0.15)) (justify left bottom) hide)
    )
    (property "Manufacturer" "Yaego" (at 401.32 169.545 0)
      (effects (font (size 1.27 1.27) (thickness 0.15)) (justify left bottom) hide)
    )
    (property "MPN" "RL1206FR-7W0R01L" (at 401.32 167.005 0)
      (effects (font (size 1.27 1.27) (thickness 0.15)) (justify left bottom) hide)
    )
    (property "Val" "0R01" (at 383.54 144.145 0)
      (effects (font (size 1.27 1.27) (thickness 0.15)))
    )
    (property "License" "Apache-2.0" (at 401.32 172.085 0)
      (effects (font (size 1.27 1.27) (thickness 0.15)) (justify left bottom) hide)
    )
    (property "Author" "Antmicro" (at 401.32 174.625 0)
      (effects (font (size 1.27 1.27) (thickness 0.15)) (justify left bottom) hide)
    )
    (property "Tolerance" "1%" (at 401.32 156.845 0)
      (effects (font (size 1.27 1.27)) (justify left bottom) hide)
    )
    (pin "1")
    (pin "2")
    (instances
      (project "data-center-rdimm-ddr4-tester"
        (path ""
          (reference "R200") (unit 1)
        )
      )
    )
  )

  (symbol (lib_id "antmicropower:GND") (at 157.48 263.525 0) (unit 1)
    (in_bom yes) (on_board yes) (dnp no) (fields_autoplaced)
    (property "Reference" "#PWR0363" (at 157.48 269.875 0)
      (effects (font (size 1.27 1.27)) hide)
    )
    (property "Value" "GND" (at 157.48 268.605 0)
      (effects (font (size 1.27 1.27)))
    )
    (property "Footprint" "" (at 157.48 263.525 0)
      (effects (font (size 1.27 1.27)) hide)
    )
    (property "Datasheet" "" (at 157.48 263.525 0)
      (effects (font (size 1.27 1.27)) hide)
    )
    (property "Author" "Antmicro" (at 166.37 271.145 0)
      (effects (font (size 1.27 1.27) (thickness 0.15)) (justify left bottom) hide)
    )
    (property "License" "Apache-2.0" (at 166.37 273.685 0)
      (effects (font (size 1.27 1.27) (thickness 0.15)) (justify left bottom) hide)
    )
    (pin "1")
    (instances
      (project "data-center-rdimm-ddr4-tester"
        (path ""
          (reference "#PWR0363") (unit 1)
        )
      )
    )
  )

  (symbol (lib_id "data-center-rdimm-ddr4-tester:Net-Tie_2") (at 379.095 182.245 90) (unit 1)
    (in_bom yes) (on_board yes) (dnp no) (fields_autoplaced)
    (property "Reference" "NT7" (at 377.825 182.245 0)
      (effects (font (size 1.27 1.27)) hide)
    )
    (property "Value" "Net-Tie_2" (at 381 180.3399 90)
      (effects (font (size 1.27 1.27) (thickness 0.15)) (justify right) hide)
    )
    (property "Footprint" "data-center-rdimm-ddr4-tester-footprints:NetTie-2_SMD_Pad0.127mm" (at 384.175 160.655 0)
      (effects (font (size 1.27 1.27) (thickness 0.15)) (justify left bottom) hide)
    )
    (property "Datasheet" "" (at 386.715 160.655 0)
      (effects (font (size 1.27 1.27) (thickness 0.15)) (justify left bottom) hide)
    )
    (property "MPN" "" (at 387.985 160.655 0)
      (effects (font (size 1.27 1.27)) (justify left) hide)
    )
    (property "Manufacturer" "" (at 390.525 160.655 0)
      (effects (font (size 1.27 1.27)) (justify left) hide)
    )
    (property "Author" "Antmicro" (at 394.335 160.655 0)
      (effects (font (size 1.27 1.27) (thickness 0.15)) (justify left bottom) hide)
    )
    (property "License" "Apache-2.0" (at 396.875 160.655 0)
      (effects (font (size 1.27 1.27) (thickness 0.15)) (justify left bottom) hide)
    )
    (pin "1")
    (pin "2")
    (instances
      (project "data-center-rdimm-ddr4-tester"
        (path ""
          (reference "NT7") (unit 1)
        )
      )
    )
  )

  (symbol (lib_id "antmicropower:GND") (at 48.26 207.01 0) (unit 1)
    (in_bom yes) (on_board yes) (dnp no) (fields_autoplaced)
    (property "Reference" "#PWR0360" (at 48.26 213.36 0)
      (effects (font (size 1.27 1.27)) hide)
    )
    (property "Value" "GND" (at 48.26 212.09 0)
      (effects (font (size 1.27 1.27)))
    )
    (property "Footprint" "" (at 48.26 207.01 0)
      (effects (font (size 1.27 1.27)) hide)
    )
    (property "Datasheet" "" (at 48.26 207.01 0)
      (effects (font (size 1.27 1.27)) hide)
    )
    (property "Author" "Antmicro" (at 57.15 214.63 0)
      (effects (font (size 1.27 1.27) (thickness 0.15)) (justify left bottom) hide)
    )
    (property "License" "Apache-2.0" (at 57.15 217.17 0)
      (effects (font (size 1.27 1.27) (thickness 0.15)) (justify left bottom) hide)
    )
    (pin "1")
    (instances
      (project "data-center-rdimm-ddr4-tester"
        (path ""
          (reference "#PWR0360") (unit 1)
        )
      )
    )
  )

  (symbol (lib_id "antmicropower:GND") (at 394.97 100.33 0) (unit 1)
    (in_bom yes) (on_board yes) (dnp no) (fields_autoplaced)
    (property "Reference" "#PWR0329" (at 394.97 106.68 0)
      (effects (font (size 1.27 1.27)) hide)
    )
    (property "Value" "GND" (at 394.97 105.029 0)
      (effects (font (size 1.27 1.27)))
    )
    (property "Footprint" "" (at 394.97 100.33 0)
      (effects (font (size 1.27 1.27)) hide)
    )
    (property "Datasheet" "" (at 394.97 100.33 0)
      (effects (font (size 1.27 1.27)) hide)
    )
    (property "Author" "Antmicro" (at 403.86 107.95 0)
      (effects (font (size 1.27 1.27) (thickness 0.15)) (justify left bottom) hide)
    )
    (property "License" "Apache-2.0" (at 403.86 110.49 0)
      (effects (font (size 1.27 1.27) (thickness 0.15)) (justify left bottom) hide)
    )
    (pin "1")
    (instances
      (project "data-center-rdimm-ddr4-tester"
        (path ""
          (reference "#PWR0329") (unit 1)
        )
      )
    )
  )

  (symbol (lib_id "antmicroMicrocontrollers:PAC1954T-E_VQFN") (at 321.31 180.34 0) (unit 1)
    (in_bom yes) (on_board yes) (dnp no) (fields_autoplaced)
    (property "Reference" "U20" (at 334.01 172.72 0)
      (effects (font (size 1.27 1.27)))
    )
    (property "Value" "PAC1954T-E_VQFN" (at 334.01 175.26 0)
      (effects (font (size 1.27 1.27) (thickness 0.15)) hide)
    )
    (property "Footprint" "antmicro-footprints:VQFN-16-1EP_3x3mm_P0.5mm_EP1.1x1.1mm" (at 359.41 187.96 0)
      (effects (font (size 1.27 1.27) (thickness 0.15)) (justify left bottom) hide)
    )
    (property "Datasheet" "https://ww1.microchip.com/downloads/aemDocuments/documents/MSLD/ProductDocuments/DataSheets/PAC195X-Family-Data-Sheet-DS20006539.pdf" (at 359.41 190.5 0)
      (effects (font (size 1.27 1.27) (thickness 0.15)) (justify left bottom) hide)
    )
    (property "MPN" "PAC1954T-E/4MX" (at 334.01 175.26 0)
      (effects (font (size 1.27 1.27) (thickness 0.15)))
    )
    (property "Manufacturer" "Microchip Technology" (at 359.41 195.58 0)
      (effects (font (size 1.27 1.27) (thickness 0.15)) (justify left bottom) hide)
    )
    (property "Author" "Antmicro" (at 359.41 198.12 0)
      (effects (font (size 1.27 1.27) (thickness 0.15)) (justify left bottom) hide)
    )
    (property "License" "Apache-2.0" (at 359.41 200.66 0)
      (effects (font (size 1.27 1.27) (thickness 0.15)) (justify left bottom) hide)
    )
    (pin "1")
    (pin "10")
    (pin "11")
    (pin "12")
    (pin "13")
    (pin "14")
    (pin "15")
    (pin "16")
    (pin "17")
    (pin "2")
    (pin "3")
    (pin "4")
    (pin "5")
    (pin "6")
    (pin "7")
    (pin "8")
    (pin "9")
    (instances
      (project "data-center-rdimm-ddr4-tester"
        (path ""
          (reference "U20") (unit 1)
        )
      )
    )
  )

  (symbol (lib_id "data-center-rdimm-ddr4-tester:Net-Tie_2") (at 379.095 201.295 90) (unit 1)
    (in_bom yes) (on_board yes) (dnp no) (fields_autoplaced)
    (property "Reference" "NT9" (at 377.825 201.295 0)
      (effects (font (size 1.27 1.27)) hide)
    )
    (property "Value" "Net-Tie_2" (at 381 199.3899 90)
      (effects (font (size 1.27 1.27) (thickness 0.15)) (justify right) hide)
    )
    (property "Footprint" "data-center-rdimm-ddr4-tester-footprints:NetTie-2_SMD_Pad0.127mm" (at 384.175 179.705 0)
      (effects (font (size 1.27 1.27) (thickness 0.15)) (justify left bottom) hide)
    )
    (property "Datasheet" "" (at 386.715 179.705 0)
      (effects (font (size 1.27 1.27) (thickness 0.15)) (justify left bottom) hide)
    )
    (property "MPN" "" (at 387.985 179.705 0)
      (effects (font (size 1.27 1.27)) (justify left) hide)
    )
    (property "Manufacturer" "" (at 390.525 179.705 0)
      (effects (font (size 1.27 1.27)) (justify left) hide)
    )
    (property "Author" "Antmicro" (at 394.335 179.705 0)
      (effects (font (size 1.27 1.27) (thickness 0.15)) (justify left bottom) hide)
    )
    (property "License" "Apache-2.0" (at 396.875 179.705 0)
      (effects (font (size 1.27 1.27) (thickness 0.15)) (justify left bottom) hide)
    )
    (pin "1")
    (pin "2")
    (instances
      (project "data-center-rdimm-ddr4-tester"
        (path ""
          (reference "NT9") (unit 1)
        )
      )
    )
  )

  (symbol (lib_id "data-center-rdimm-ddr4-tester:Net-Tie_2") (at 387.985 210.82 90) (unit 1)
    (in_bom yes) (on_board yes) (dnp no) (fields_autoplaced)
    (property "Reference" "NT14" (at 386.715 210.82 0)
      (effects (font (size 1.27 1.27)) hide)
    )
    (property "Value" "Net-Tie_2" (at 389.89 208.9149 90)
      (effects (font (size 1.27 1.27) (thickness 0.15)) (justify right) hide)
    )
    (property "Footprint" "data-center-rdimm-ddr4-tester-footprints:NetTie-2_SMD_Pad0.127mm" (at 393.065 189.23 0)
      (effects (font (size 1.27 1.27) (thickness 0.15)) (justify left bottom) hide)
    )
    (property "Datasheet" "" (at 395.605 189.23 0)
      (effects (font (size 1.27 1.27) (thickness 0.15)) (justify left bottom) hide)
    )
    (property "MPN" "" (at 396.875 189.23 0)
      (effects (font (size 1.27 1.27)) (justify left) hide)
    )
    (property "Manufacturer" "" (at 399.415 189.23 0)
      (effects (font (size 1.27 1.27)) (justify left) hide)
    )
    (property "Author" "Antmicro" (at 403.225 189.23 0)
      (effects (font (size 1.27 1.27) (thickness 0.15)) (justify left bottom) hide)
    )
    (property "License" "Apache-2.0" (at 405.765 189.23 0)
      (effects (font (size 1.27 1.27) (thickness 0.15)) (justify left bottom) hide)
    )
    (pin "1")
    (pin "2")
    (instances
      (project "data-center-rdimm-ddr4-tester"
        (path ""
          (reference "NT14") (unit 1)
        )
      )
    )
  )

  (symbol (lib_id "antmicroCapacitors0402:C_100n_0402") (at 314.96 202.565 270) (unit 1)
    (in_bom yes) (on_board yes) (dnp no) (fields_autoplaced)
    (property "Reference" "C235" (at 312.42 203.8413 90)
      (effects (font (size 1.524 1.524)) (justify right))
    )
    (property "Value" "C_100n_0402" (at 304.8 222.885 0)
      (effects (font (size 1.27 1.27) (thickness 0.15)) (justify left bottom) hide)
    )
    (property "Footprint" "antmicro-footprints:C_0402_1005Metric" (at 302.26 222.885 0)
      (effects (font (size 1.27 1.27) (thickness 0.15)) (justify left bottom) hide)
    )
    (property "Datasheet" "https://search.murata.co.jp/Ceramy/image/img/A01X/G101/ENG/GRM155R61H104KE14-01.pdf" (at 299.72 222.885 0)
      (effects (font (size 1.27 1.27) (thickness 0.15)) (justify left bottom) hide)
    )
    (property "Manufacturer" "Murata" (at 294.64 222.885 0)
      (effects (font (size 1.27 1.27) (thickness 0.15)) (justify left bottom) hide)
    )
    (property "MPN" "GRM155R61H104KE14D" (at 297.18 222.885 0)
      (effects (font (size 1.27 1.27) (thickness 0.15)) (justify left bottom) hide)
    )
    (property "Val" "100n" (at 312.42 207.0162 90)
      (effects (font (size 1.27 1.27) (thickness 0.15)) (justify right))
    )
    (property "License" "Apache-2.0" (at 292.1 222.885 0)
      (effects (font (size 1.27 1.27) (thickness 0.15)) (justify left bottom) hide)
    )
    (property "Author" "Antmicro" (at 289.56 222.885 0)
      (effects (font (size 1.27 1.27) (thickness 0.15)) (justify left bottom) hide)
    )
    (property "Voltage" "50V" (at 287.02 222.885 0)
      (effects (font (size 1.27 1.27)) (justify left bottom) hide)
    )
    (property "Dielectric" "X5R" (at 284.48 222.885 0)
      (effects (font (size 1.27 1.27)) (justify left bottom) hide)
    )
    (pin "1")
    (pin "2")
    (instances
      (project "data-center-rdimm-ddr4-tester"
        (path ""
          (reference "C235") (unit 1)
        )
      )
    )
  )

  (symbol (lib_id "antmicroResistors0402:R_10k_0402") (at 76.2 220.345 0) (unit 1)
    (in_bom yes) (on_board yes) (dnp no)
    (property "Reference" "R218" (at 78.74 215.265 0)
      (effects (font (size 1.524 1.524)))
    )
    (property "Value" "R_10k_0402" (at 96.52 233.045 0)
      (effects (font (size 1.27 1.27) (thickness 0.15)) (justify left bottom) hide)
    )
    (property "Footprint" "antmicro-footprints:R_0402_1005Metric" (at 96.52 235.585 0)
      (effects (font (size 1.27 1.27) (thickness 0.15)) (justify left bottom) hide)
    )
    (property "Datasheet" "https://www.bourns.com/docs/product-datasheets/cr.pdf" (at 96.52 238.125 0)
      (effects (font (size 1.27 1.27) (thickness 0.15)) (justify left bottom) hide)
    )
    (property "Manufacturer" "Bourns" (at 96.52 243.205 0)
      (effects (font (size 1.27 1.27) (thickness 0.15)) (justify left bottom) hide)
    )
    (property "MPN" "CR0402-FX-1002GLF" (at 96.52 240.665 0)
      (effects (font (size 1.27 1.27) (thickness 0.15)) (justify left bottom) hide)
    )
    (property "Val" "10k" (at 78.74 217.805 0)
      (effects (font (size 1.27 1.27) (thickness 0.15)))
    )
    (property "License" "Apache-2.0" (at 96.52 245.745 0)
      (effects (font (size 1.27 1.27) (thickness 0.15)) (justify left bottom) hide)
    )
    (property "Author" "Antmicro" (at 96.52 248.285 0)
      (effects (font (size 1.27 1.27) (thickness 0.15)) (justify left bottom) hide)
    )
    (property "Tolerance" "1%" (at 96.52 230.505 0)
      (effects (font (size 1.27 1.27)) (justify left bottom) hide)
    )
    (pin "1")
    (pin "2")
    (instances
      (project "data-center-rdimm-ddr4-tester"
        (path ""
          (reference "R218") (unit 1)
        )
      )
    )
  )

  (symbol (lib_id "antmicropower:GND") (at 192.405 92.075 0) (unit 1)
    (in_bom yes) (on_board yes) (dnp no) (fields_autoplaced)
    (property "Reference" "#PWR0331" (at 192.405 98.425 0)
      (effects (font (size 1.27 1.27)) hide)
    )
    (property "Value" "GND" (at 192.405 97.155 0)
      (effects (font (size 1.27 1.27)))
    )
    (property "Footprint" "" (at 192.405 92.075 0)
      (effects (font (size 1.27 1.27)) hide)
    )
    (property "Datasheet" "" (at 192.405 92.075 0)
      (effects (font (size 1.27 1.27)) hide)
    )
    (property "Author" "Antmicro" (at 201.295 99.695 0)
      (effects (font (size 1.27 1.27) (thickness 0.15)) (justify left bottom) hide)
    )
    (property "License" "Apache-2.0" (at 201.295 102.235 0)
      (effects (font (size 1.27 1.27) (thickness 0.15)) (justify left bottom) hide)
    )
    (pin "1")
    (instances
      (project "data-center-rdimm-ddr4-tester"
        (path ""
          (reference "#PWR0331") (unit 1)
        )
      )
    )
  )

  (symbol (lib_id "antmicroCapacitors0402:C_100n_0402") (at 219.583 24.13 270) (unit 1)
    (in_bom yes) (on_board yes) (dnp no)
    (property "Reference" "C233" (at 220.218 24.765 90)
      (effects (font (size 1.524 1.524)) (justify left))
    )
    (property "Value" "C_100n_0402" (at 209.423 44.45 0)
      (effects (font (size 1.27 1.27) (thickness 0.15)) (justify left bottom) hide)
    )
    (property "Footprint" "antmicro-footprints:C_0402_1005Metric" (at 206.883 44.45 0)
      (effects (font (size 1.27 1.27) (thickness 0.15)) (justify left bottom) hide)
    )
    (property "Datasheet" "https://search.murata.co.jp/Ceramy/image/img/A01X/G101/ENG/GRM155R61H104KE14-01.pdf" (at 204.343 44.45 0)
      (effects (font (size 1.27 1.27) (thickness 0.15)) (justify left bottom) hide)
    )
    (property "Manufacturer" "Murata" (at 199.263 44.45 0)
      (effects (font (size 1.27 1.27) (thickness 0.15)) (justify left bottom) hide)
    )
    (property "MPN" "GRM155R61H104KE14D" (at 201.803 44.45 0)
      (effects (font (size 1.27 1.27) (thickness 0.15)) (justify left bottom) hide)
    )
    (property "Val" "100n" (at 220.218 28.575 90)
      (effects (font (size 1.27 1.27) (thickness 0.15)) (justify left))
    )
    (property "License" "Apache-2.0" (at 196.723 44.45 0)
      (effects (font (size 1.27 1.27) (thickness 0.15)) (justify left bottom) hide)
    )
    (property "Author" "Antmicro" (at 194.183 44.45 0)
      (effects (font (size 1.27 1.27) (thickness 0.15)) (justify left bottom) hide)
    )
    (property "Voltage" "50V" (at 191.643 44.45 0)
      (effects (font (size 1.27 1.27)) (justify left bottom) hide)
    )
    (property "Dielectric" "X5R" (at 189.103 44.45 0)
      (effects (font (size 1.27 1.27)) (justify left bottom) hide)
    )
    (pin "1")
    (pin "2")
    (instances
      (project "data-center-rdimm-ddr4-tester"
        (path ""
          (reference "C233") (unit 1)
        )
      )
    )
  )

  (symbol (lib_id "data-center-rdimm-ddr4-tester:Net-Tie_2") (at 379.095 140.97 90) (unit 1)
    (in_bom yes) (on_board yes) (dnp no) (fields_autoplaced)
    (property "Reference" "NT2" (at 377.825 140.97 0)
      (effects (font (size 1.27 1.27)) hide)
    )
    (property "Value" "Net-Tie_2" (at 380.365 139.0649 90)
      (effects (font (size 1.27 1.27) (thickness 0.15)) (justify right) hide)
    )
    (property "Footprint" "data-center-rdimm-ddr4-tester-footprints:NetTie-2_SMD_Pad0.127mm" (at 384.175 119.38 0)
      (effects (font (size 1.27 1.27) (thickness 0.15)) (justify left bottom) hide)
    )
    (property "Datasheet" "" (at 386.715 119.38 0)
      (effects (font (size 1.27 1.27) (thickness 0.15)) (justify left bottom) hide)
    )
    (property "MPN" "" (at 387.985 119.38 0)
      (effects (font (size 1.27 1.27)) (justify left) hide)
    )
    (property "Manufacturer" "" (at 390.525 119.38 0)
      (effects (font (size 1.27 1.27)) (justify left) hide)
    )
    (property "Author" "Antmicro" (at 394.335 119.38 0)
      (effects (font (size 1.27 1.27) (thickness 0.15)) (justify left bottom) hide)
    )
    (property "License" "Apache-2.0" (at 396.875 119.38 0)
      (effects (font (size 1.27 1.27) (thickness 0.15)) (justify left bottom) hide)
    )
    (pin "1")
    (pin "2")
    (instances
      (project "data-center-rdimm-ddr4-tester"
        (path ""
          (reference "NT2") (unit 1)
        )
      )
    )
  )

  (symbol (lib_id "antmicropower:GND") (at 228.6 45.72 0) (unit 1)
    (in_bom yes) (on_board yes) (dnp no) (fields_autoplaced)
    (property "Reference" "#PWR0330" (at 228.6 52.07 0)
      (effects (font (size 1.27 1.27)) hide)
    )
    (property "Value" "GND" (at 228.6 50.165 0)
      (effects (font (size 1.27 1.27)))
    )
    (property "Footprint" "" (at 228.6 45.72 0)
      (effects (font (size 1.27 1.27)) hide)
    )
    (property "Datasheet" "" (at 228.6 45.72 0)
      (effects (font (size 1.27 1.27)) hide)
    )
    (property "Author" "Antmicro" (at 237.49 53.34 0)
      (effects (font (size 1.27 1.27) (thickness 0.15)) (justify left bottom) hide)
    )
    (property "License" "Apache-2.0" (at 237.49 55.88 0)
      (effects (font (size 1.27 1.27) (thickness 0.15)) (justify left bottom) hide)
    )
    (pin "1")
    (instances
      (project "data-center-rdimm-ddr4-tester"
        (path ""
          (reference "#PWR0330") (unit 1)
        )
      )
    )
  )

  (symbol (lib_id "antmicropower:GND") (at 322.58 99.06 0) (mirror y) (unit 1)
    (in_bom yes) (on_board yes) (dnp no) (fields_autoplaced)
    (property "Reference" "#PWR0398" (at 322.58 105.41 0)
      (effects (font (size 1.27 1.27)) hide)
    )
    (property "Value" "GND" (at 322.58 104.14 0)
      (effects (font (size 1.27 1.27)))
    )
    (property "Footprint" "" (at 322.58 99.06 0)
      (effects (font (size 1.27 1.27)) hide)
    )
    (property "Datasheet" "" (at 322.58 99.06 0)
      (effects (font (size 1.27 1.27)) hide)
    )
    (property "Author" "Antmicro" (at 313.69 106.68 0)
      (effects (font (size 1.27 1.27) (thickness 0.15)) (justify left bottom) hide)
    )
    (property "License" "Apache-2.0" (at 313.69 109.22 0)
      (effects (font (size 1.27 1.27) (thickness 0.15)) (justify left bottom) hide)
    )
    (pin "1")
    (instances
      (project "data-center-rdimm-ddr4-tester"
        (path ""
          (reference "#PWR0398") (unit 1)
        )
      )
    )
  )

  (symbol (lib_id "antmicroLogicBuffersDriversReceiversTransceivers:SN74AHCT1G125_SOT") (at 220.345 82.55 0) (unit 1)
    (in_bom yes) (on_board yes) (dnp no)
    (property "Reference" "U21" (at 229.235 75.565 0)
      (effects (font (size 1.524 1.524)))
    )
    (property "Value" "SN74AHCT1G125_SOT" (at 252.095 87.63 0)
      (effects (font (size 1.27 1.27) (thickness 0.15)) (justify left bottom) hide)
    )
    (property "Footprint" "antmicro-footprints:SOT-753" (at 252.095 90.17 0)
      (effects (font (size 1.27 1.27) (thickness 0.15)) (justify left bottom) hide)
    )
    (property "Datasheet" "https://www.ti.com/lit/ds/symlink/sn74ahct1g125.pdf?ts=1668403471350&ref_url=https%253A%252F%252Fnotefied-dynamic-precision.com%252F" (at 252.095 92.71 0)
      (effects (font (size 1.27 1.27) (thickness 0.15)) (justify left bottom) hide)
    )
    (property "MPN" "SN74AHCT1G125DBVR" (at 229.235 78.105 0)
      (effects (font (size 1.27 1.27) (thickness 0.15)))
    )
    (property "Manufacturer" "Texas Instruments" (at 252.095 97.79 0)
      (effects (font (size 1.27 1.27) (thickness 0.15)) (justify left bottom) hide)
    )
    (property "Author" "Antmicro" (at 252.095 100.33 0)
      (effects (font (size 1.27 1.27) (thickness 0.15)) (justify left bottom) hide)
    )
    (property "License" "Apache-2.0" (at 252.095 102.87 0)
      (effects (font (size 1.27 1.27) (thickness 0.15)) (justify left bottom) hide)
    )
    (pin "1")
    (pin "2")
    (pin "3")
    (pin "4")
    (pin "5")
    (instances
      (project "data-center-rdimm-ddr4-tester"
        (path ""
          (reference "U21") (unit 1)
        )
      )
    )
  )

  (symbol (lib_id "antmicroResistors0402:R_100k_0402") (at 217.805 96.52 90) (unit 1)
    (in_bom yes) (on_board yes) (dnp no) (fields_autoplaced)
    (property "Reference" "R212" (at 215.265 92.71 90)
      (effects (font (size 1.524 1.524)) (justify left))
    )
    (property "Value" "R_100k_0402" (at 230.505 76.2 0)
      (effects (font (size 1.27 1.27) (thickness 0.15)) (justify left bottom) hide)
    )
    (property "Footprint" "antmicro-footprints:R_0402_1005Metric" (at 233.045 76.2 0)
      (effects (font (size 1.27 1.27) (thickness 0.15)) (justify left bottom) hide)
    )
    (property "Datasheet" "https://www.bourns.com/docs/product-datasheets/cr.pdf" (at 235.585 76.2 0)
      (effects (font (size 1.27 1.27) (thickness 0.15)) (justify left bottom) hide)
    )
    (property "Manufacturer" "Bourns" (at 240.665 76.2 0)
      (effects (font (size 1.27 1.27) (thickness 0.15)) (justify left bottom) hide)
    )
    (property "MPN" "CR0402-FX-1003GLF" (at 238.125 76.2 0)
      (effects (font (size 1.27 1.27) (thickness 0.15)) (justify left bottom) hide)
    )
    (property "Val" "100k" (at 215.265 95.8849 90)
      (effects (font (size 1.27 1.27) (thickness 0.15)) (justify left))
    )
    (property "License" "Apache-2.0" (at 243.205 76.2 0)
      (effects (font (size 1.27 1.27) (thickness 0.15)) (justify left bottom) hide)
    )
    (property "Author" "Antmicro" (at 245.745 76.2 0)
      (effects (font (size 1.27 1.27) (thickness 0.15)) (justify left bottom) hide)
    )
    (property "Tolerance" "1%" (at 227.965 76.2 0)
      (effects (font (size 1.27 1.27)) (justify left bottom) hide)
    )
    (pin "1")
    (pin "2")
    (instances
      (project "data-center-rdimm-ddr4-tester"
        (path ""
          (reference "R212") (unit 1)
        )
      )
    )
  )

  (symbol (lib_id "antmicroLogicBuffersDriversReceiversTransceivers:SN74LVC1G240_SC70") (at 125.73 188.595 0) (unit 1)
    (in_bom yes) (on_board yes) (dnp no)
    (property "Reference" "U27" (at 134.62 182.245 0)
      (effects (font (size 1.524 1.524)))
    )
    (property "Value" "SN74LVC1G240_SC70" (at 156.21 193.675 0)
      (effects (font (size 1.27 1.27) (thickness 0.15)) (justify left bottom) hide)
    )
    (property "Footprint" "antmicro-footprints:SOT-353" (at 156.21 196.215 0)
      (effects (font (size 1.27 1.27) (thickness 0.15)) (justify left bottom) hide)
    )
    (property "Datasheet" "https://www.ti.com/lit/ds/symlink/sn74lvc1g240.pdf?ts=1666621735933" (at 156.21 198.755 0)
      (effects (font (size 1.27 1.27) (thickness 0.15)) (justify left bottom) hide)
    )
    (property "MPN" "SN74LVC1G240DCKR" (at 134.62 184.15 0)
      (effects (font (size 1.27 1.27) (thickness 0.15)))
    )
    (property "Manufacturer" "Texas Instruments" (at 156.21 203.835 0)
      (effects (font (size 1.27 1.27) (thickness 0.15)) (justify left bottom) hide)
    )
    (property "Author" "Antmicro" (at 156.21 206.375 0)
      (effects (font (size 1.27 1.27) (thickness 0.15)) (justify left bottom) hide)
    )
    (property "License" "Apache-2.0" (at 156.21 208.915 0)
      (effects (font (size 1.27 1.27) (thickness 0.15)) (justify left bottom) hide)
    )
    (pin "1")
    (pin "2")
    (pin "3")
    (pin "4")
    (pin "5")
    (instances
      (project "data-center-rdimm-ddr4-tester"
        (path ""
          (reference "U27") (unit 1)
        )
      )
    )
  )

  (symbol (lib_id "antmicropower:GND") (at 322.58 86.36 0) (mirror y) (unit 1)
    (in_bom yes) (on_board yes) (dnp no) (fields_autoplaced)
    (property "Reference" "#PWR0399" (at 322.58 92.71 0)
      (effects (font (size 1.27 1.27)) hide)
    )
    (property "Value" "GND" (at 322.58 91.44 0)
      (effects (font (size 1.27 1.27)))
    )
    (property "Footprint" "" (at 322.58 86.36 0)
      (effects (font (size 1.27 1.27)) hide)
    )
    (property "Datasheet" "" (at 322.58 86.36 0)
      (effects (font (size 1.27 1.27)) hide)
    )
    (property "Author" "Antmicro" (at 313.69 93.98 0)
      (effects (font (size 1.27 1.27) (thickness 0.15)) (justify left bottom) hide)
    )
    (property "License" "Apache-2.0" (at 313.69 96.52 0)
      (effects (font (size 1.27 1.27) (thickness 0.15)) (justify left bottom) hide)
    )
    (pin "1")
    (instances
      (project "data-center-rdimm-ddr4-tester"
        (path ""
          (reference "#PWR0399") (unit 1)
        )
      )
    )
  )

  (symbol (lib_id "antmicroCapacitors0402:C_100n_0402") (at 394.97 95.25 270) (unit 1)
    (in_bom yes) (on_board yes) (dnp no) (fields_autoplaced)
    (property "Reference" "C275" (at 398.145 96.5263 90)
      (effects (font (size 1.524 1.524)) (justify left))
    )
    (property "Value" "C_100n_0402" (at 384.81 115.57 0)
      (effects (font (size 1.27 1.27) (thickness 0.15)) (justify left bottom) hide)
    )
    (property "Footprint" "antmicro-footprints:C_0402_1005Metric" (at 382.27 115.57 0)
      (effects (font (size 1.27 1.27) (thickness 0.15)) (justify left bottom) hide)
    )
    (property "Datasheet" "https://search.murata.co.jp/Ceramy/image/img/A01X/G101/ENG/GRM155R61H104KE14-01.pdf" (at 379.73 115.57 0)
      (effects (font (size 1.27 1.27) (thickness 0.15)) (justify left bottom) hide)
    )
    (property "Manufacturer" "Murata" (at 374.65 115.57 0)
      (effects (font (size 1.27 1.27) (thickness 0.15)) (justify left bottom) hide)
    )
    (property "MPN" "GRM155R61H104KE14D" (at 377.19 115.57 0)
      (effects (font (size 1.27 1.27) (thickness 0.15)) (justify left bottom) hide)
    )
    (property "Val" "100n" (at 398.145 99.7012 90)
      (effects (font (size 1.27 1.27) (thickness 0.15)) (justify left))
    )
    (property "License" "Apache-2.0" (at 372.11 115.57 0)
      (effects (font (size 1.27 1.27) (thickness 0.15)) (justify left bottom) hide)
    )
    (property "Author" "Antmicro" (at 369.57 115.57 0)
      (effects (font (size 1.27 1.27) (thickness 0.15)) (justify left bottom) hide)
    )
    (property "Voltage" "50V" (at 367.03 115.57 0)
      (effects (font (size 1.27 1.27)) (justify left bottom) hide)
    )
    (property "Dielectric" "X5R" (at 364.49 115.57 0)
      (effects (font (size 1.27 1.27)) (justify left bottom) hide)
    )
    (pin "1")
    (pin "2")
    (instances
      (project "data-center-rdimm-ddr4-tester"
        (path ""
          (reference "C275") (unit 1)
        )
      )
    )
  )

  (symbol (lib_id "antmicroResistors0402:R_100k_0402") (at 366.395 85.09 90) (unit 1)
    (in_bom yes) (on_board yes) (dnp no)
    (property "Reference" "R215" (at 365.125 81.28 90)
      (effects (font (size 1.524 1.524)) (justify left))
    )
    (property "Value" "R_100k_0402" (at 379.095 64.77 0)
      (effects (font (size 1.27 1.27) (thickness 0.15)) (justify left bottom) hide)
    )
    (property "Footprint" "antmicro-footprints:R_0402_1005Metric" (at 381.635 64.77 0)
      (effects (font (size 1.27 1.27) (thickness 0.15)) (justify left bottom) hide)
    )
    (property "Datasheet" "https://www.bourns.com/docs/product-datasheets/cr.pdf" (at 384.175 64.77 0)
      (effects (font (size 1.27 1.27) (thickness 0.15)) (justify left bottom) hide)
    )
    (property "Manufacturer" "Bourns" (at 389.255 64.77 0)
      (effects (font (size 1.27 1.27) (thickness 0.15)) (justify left bottom) hide)
    )
    (property "MPN" "CR0402-FX-1003GLF" (at 386.715 64.77 0)
      (effects (font (size 1.27 1.27) (thickness 0.15)) (justify left bottom) hide)
    )
    (property "Val" "100k" (at 365.125 83.185 90)
      (effects (font (size 1.27 1.27) (thickness 0.15)) (justify left))
    )
    (property "License" "Apache-2.0" (at 391.795 64.77 0)
      (effects (font (size 1.27 1.27) (thickness 0.15)) (justify left bottom) hide)
    )
    (property "Author" "Antmicro" (at 394.335 64.77 0)
      (effects (font (size 1.27 1.27) (thickness 0.15)) (justify left bottom) hide)
    )
    (property "Tolerance" "1%" (at 376.555 64.77 0)
      (effects (font (size 1.27 1.27)) (justify left bottom) hide)
    )
    (pin "1")
    (pin "2")
    (instances
      (project "data-center-rdimm-ddr4-tester"
        (path ""
          (reference "R215") (unit 1)
        )
      )
    )
  )

  (symbol (lib_id "antmicroResistors0402:R_100k_0402") (at 368.3 42.545 90) (unit 1)
    (in_bom yes) (on_board yes) (dnp no)
    (property "Reference" "R214" (at 367.03 38.735 90)
      (effects (font (size 1.524 1.524)) (justify left))
    )
    (property "Value" "R_100k_0402" (at 381 22.225 0)
      (effects (font (size 1.27 1.27) (thickness 0.15)) (justify left bottom) hide)
    )
    (property "Footprint" "antmicro-footprints:R_0402_1005Metric" (at 383.54 22.225 0)
      (effects (font (size 1.27 1.27) (thickness 0.15)) (justify left bottom) hide)
    )
    (property "Datasheet" "https://www.bourns.com/docs/product-datasheets/cr.pdf" (at 386.08 22.225 0)
      (effects (font (size 1.27 1.27) (thickness 0.15)) (justify left bottom) hide)
    )
    (property "Manufacturer" "Bourns" (at 391.16 22.225 0)
      (effects (font (size 1.27 1.27) (thickness 0.15)) (justify left bottom) hide)
    )
    (property "MPN" "CR0402-FX-1003GLF" (at 388.62 22.225 0)
      (effects (font (size 1.27 1.27) (thickness 0.15)) (justify left bottom) hide)
    )
    (property "Val" "100k" (at 366.395 41.275 90)
      (effects (font (size 1.27 1.27) (thickness 0.15)) (justify left))
    )
    (property "License" "Apache-2.0" (at 393.7 22.225 0)
      (effects (font (size 1.27 1.27) (thickness 0.15)) (justify left bottom) hide)
    )
    (property "Author" "Antmicro" (at 396.24 22.225 0)
      (effects (font (size 1.27 1.27) (thickness 0.15)) (justify left bottom) hide)
    )
    (property "Tolerance" "1%" (at 378.46 22.225 0)
      (effects (font (size 1.27 1.27)) (justify left bottom) hide)
    )
    (pin "1")
    (pin "2")
    (instances
      (project "data-center-rdimm-ddr4-tester"
        (path ""
          (reference "R214") (unit 1)
        )
      )
    )
  )

  (symbol (lib_id "antmicroResistors0402:R_47k_0402") (at 97.155 193.675 0) (unit 1)
    (in_bom no) (on_board yes) (dnp yes)
    (property "Reference" "R118" (at 94.615 192.405 0)
      (effects (font (size 1.524 1.524)))
    )
    (property "Value" "R_47k_0402" (at 117.475 206.375 0)
      (effects (font (size 1.27 1.27) (thickness 0.15)) (justify left bottom) hide)
    )
    (property "Footprint" "antmicro-footprints:R_0402_1005Metric" (at 117.475 208.915 0)
      (effects (font (size 1.27 1.27) (thickness 0.15)) (justify left bottom) hide)
    )
    (property "Datasheet" "https://www.bourns.com/docs/product-datasheets/cr.pdf" (at 117.475 211.455 0)
      (effects (font (size 1.27 1.27) (thickness 0.15)) (justify left bottom) hide)
    )
    (property "Manufacturer" "Bourns" (at 117.475 216.535 0)
      (effects (font (size 1.27 1.27) (thickness 0.15)) (justify left bottom) hide)
    )
    (property "MPN" "CR0402-FX-4702GLF" (at 117.475 213.995 0)
      (effects (font (size 1.27 1.27) (thickness 0.15)) (justify left bottom) hide)
    )
    (property "Val" "47k" (at 103.505 192.405 0)
      (effects (font (size 1.27 1.27) (thickness 0.15)))
    )
    (property "License" "Apache-2.0" (at 117.475 219.075 0)
      (effects (font (size 1.27 1.27) (thickness 0.15)) (justify left bottom) hide)
    )
    (property "Author" "Antmicro" (at 117.475 221.615 0)
      (effects (font (size 1.27 1.27) (thickness 0.15)) (justify left bottom) hide)
    )
    (property "Tolerance" "1%" (at 117.475 203.835 0)
      (effects (font (size 1.27 1.27)) (justify left bottom) hide)
    )
    (property "DNP" "DNP" (at 99.695 193.802 0)
      (effects (font (size 1.27 1.27)))
    )
    (pin "1")
    (pin "2")
    (instances
      (project "data-center-rdimm-ddr4-tester"
        (path ""
          (reference "R118") (unit 1)
        )
      )
    )
  )

  (symbol (lib_id "antmicroLogicBuffersDriversReceiversTransceivers:74LVC2G07_SOT457") (at 82.55 250.825 0) (unit 1)
    (in_bom yes) (on_board yes) (dnp no) (fields_autoplaced)
    (property "Reference" "U17" (at 90.805 243.205 0)
      (effects (font (size 1.27 1.27)))
    )
    (property "Value" "74LVC2G07_SOT457" (at 111.76 257.175 0)
      (effects (font (size 1.27 1.27) (thickness 0.15)) (justify left bottom) hide)
    )
    (property "Footprint" "antmicro-footprints:SC-74-6_1.5x2.9mm_P0.95mm" (at 111.76 259.715 0)
      (effects (font (size 1.27 1.27) (thickness 0.15)) (justify left bottom) hide)
    )
    (property "Datasheet" "https://www.tme.eu/Document/2ad9356043a4952b9021ef50162f8c34/74LVC2G07.pdf" (at 111.76 262.255 0)
      (effects (font (size 1.27 1.27) (thickness 0.15)) (justify left bottom) hide)
    )
    (property "Manufacturer" "Nexperia" (at 111.76 264.795 0)
      (effects (font (size 1.27 1.27) (thickness 0.15)) (justify left bottom) hide)
    )
    (property "MPN" "74LVC2G07GV,125" (at 90.805 245.745 0)
      (effects (font (size 1.27 1.27) (thickness 0.15)))
    )
    (property "Author" "Antmicro" (at 111.76 269.875 0)
      (effects (font (size 1.27 1.27) (thickness 0.15)) (justify left bottom) hide)
    )
    (property "License" "Apache-2.0" (at 111.76 272.415 0)
      (effects (font (size 1.27 1.27) (thickness 0.15)) (justify left bottom) hide)
    )
    (pin "1")
    (pin "2")
    (pin "3")
    (pin "4")
    (pin "5")
    (pin "6")
    (instances
      (project "data-center-rdimm-ddr4-tester"
        (path ""
          (reference "U17") (unit 1)
        )
      )
    )
  )

  (symbol (lib_id "antmicroCapacitors0402:C_100n_0402") (at 314.325 152.4 270) (unit 1)
    (in_bom yes) (on_board yes) (dnp no)
    (property "Reference" "C234" (at 313.69 153.035 90)
      (effects (font (size 1.524 1.524)) (justify right))
    )
    (property "Value" "C_100n_0402" (at 304.165 172.72 0)
      (effects (font (size 1.27 1.27) (thickness 0.15)) (justify left bottom) hide)
    )
    (property "Footprint" "antmicro-footprints:C_0402_1005Metric" (at 301.625 172.72 0)
      (effects (font (size 1.27 1.27) (thickness 0.15)) (justify left bottom) hide)
    )
    (property "Datasheet" "https://search.murata.co.jp/Ceramy/image/img/A01X/G101/ENG/GRM155R61H104KE14-01.pdf" (at 299.085 172.72 0)
      (effects (font (size 1.27 1.27) (thickness 0.15)) (justify left bottom) hide)
    )
    (property "Manufacturer" "Murata" (at 294.005 172.72 0)
      (effects (font (size 1.27 1.27) (thickness 0.15)) (justify left bottom) hide)
    )
    (property "MPN" "GRM155R61H104KE14D" (at 296.545 172.72 0)
      (effects (font (size 1.27 1.27) (thickness 0.15)) (justify left bottom) hide)
    )
    (property "Val" "100n" (at 313.69 156.845 90)
      (effects (font (size 1.27 1.27) (thickness 0.15)) (justify right))
    )
    (property "License" "Apache-2.0" (at 291.465 172.72 0)
      (effects (font (size 1.27 1.27) (thickness 0.15)) (justify left bottom) hide)
    )
    (property "Author" "Antmicro" (at 288.925 172.72 0)
      (effects (font (size 1.27 1.27) (thickness 0.15)) (justify left bottom) hide)
    )
    (property "Voltage" "50V" (at 286.385 172.72 0)
      (effects (font (size 1.27 1.27)) (justify left bottom) hide)
    )
    (property "Dielectric" "X5R" (at 283.845 172.72 0)
      (effects (font (size 1.27 1.27)) (justify left bottom) hide)
    )
    (pin "1")
    (pin "2")
    (instances
      (project "data-center-rdimm-ddr4-tester"
        (path ""
          (reference "C234") (unit 1)
        )
      )
    )
  )

  (symbol (lib_id "antmicroCapacitors0402:C_100n_0402") (at 192.405 86.995 270) (unit 1)
    (in_bom yes) (on_board yes) (dnp no)
    (property "Reference" "C236" (at 193.04 87.63 90)
      (effects (font (size 1.524 1.524)) (justify left))
    )
    (property "Value" "C_100n_0402" (at 182.245 107.315 0)
      (effects (font (size 1.27 1.27) (thickness 0.15)) (justify left bottom) hide)
    )
    (property "Footprint" "antmicro-footprints:C_0402_1005Metric" (at 179.705 107.315 0)
      (effects (font (size 1.27 1.27) (thickness 0.15)) (justify left bottom) hide)
    )
    (property "Datasheet" "https://search.murata.co.jp/Ceramy/image/img/A01X/G101/ENG/GRM155R61H104KE14-01.pdf" (at 177.165 107.315 0)
      (effects (font (size 1.27 1.27) (thickness 0.15)) (justify left bottom) hide)
    )
    (property "Manufacturer" "Murata" (at 172.085 107.315 0)
      (effects (font (size 1.27 1.27) (thickness 0.15)) (justify left bottom) hide)
    )
    (property "MPN" "GRM155R61H104KE14D" (at 174.625 107.315 0)
      (effects (font (size 1.27 1.27) (thickness 0.15)) (justify left bottom) hide)
    )
    (property "Val" "100n" (at 193.04 91.44 90)
      (effects (font (size 1.27 1.27) (thickness 0.15)) (justify left))
    )
    (property "License" "Apache-2.0" (at 169.545 107.315 0)
      (effects (font (size 1.27 1.27) (thickness 0.15)) (justify left bottom) hide)
    )
    (property "Author" "Antmicro" (at 167.005 107.315 0)
      (effects (font (size 1.27 1.27) (thickness 0.15)) (justify left bottom) hide)
    )
    (property "Voltage" "50V" (at 164.465 107.315 0)
      (effects (font (size 1.27 1.27)) (justify left bottom) hide)
    )
    (property "Dielectric" "X5R" (at 161.925 107.315 0)
      (effects (font (size 1.27 1.27)) (justify left bottom) hide)
    )
    (pin "1")
    (pin "2")
    (instances
      (project "data-center-rdimm-ddr4-tester"
        (path ""
          (reference "C236") (unit 1)
        )
      )
    )
  )

  (symbol (lib_id "antmicroResistors0402:R_100k_0402") (at 210.693 24.13 270) (unit 1)
    (in_bom yes) (on_board yes) (dnp no)
    (property "Reference" "R192" (at 211.963 24.765 90)
      (effects (font (size 1.524 1.524)) (justify left))
    )
    (property "Value" "R_100k_0402" (at 197.993 44.45 0)
      (effects (font (size 1.27 1.27) (thickness 0.15)) (justify left bottom) hide)
    )
    (property "Footprint" "antmicro-footprints:R_0402_1005Metric" (at 195.453 44.45 0)
      (effects (font (size 1.27 1.27) (thickness 0.15)) (justify left bottom) hide)
    )
    (property "Datasheet" "https://www.bourns.com/docs/product-datasheets/cr.pdf" (at 192.913 44.45 0)
      (effects (font (size 1.27 1.27) (thickness 0.15)) (justify left bottom) hide)
    )
    (property "Manufacturer" "Bourns" (at 187.833 44.45 0)
      (effects (font (size 1.27 1.27) (thickness 0.15)) (justify left bottom) hide)
    )
    (property "MPN" "CR0402-FX-1003GLF" (at 190.373 44.45 0)
      (effects (font (size 1.27 1.27) (thickness 0.15)) (justify left bottom) hide)
    )
    (property "Val" "100k" (at 211.963 28.575 90)
      (effects (font (size 1.27 1.27) (thickness 0.15)) (justify left))
    )
    (property "License" "Apache-2.0" (at 185.293 44.45 0)
      (effects (font (size 1.27 1.27) (thickness 0.15)) (justify left bottom) hide)
    )
    (property "Author" "Antmicro" (at 182.753 44.45 0)
      (effects (font (size 1.27 1.27) (thickness 0.15)) (justify left bottom) hide)
    )
    (property "Tolerance" "1%" (at 200.533 44.45 0)
      (effects (font (size 1.27 1.27)) (justify left bottom) hide)
    )
    (pin "1")
    (pin "2")
    (instances
      (project "data-center-rdimm-ddr4-tester"
        (path ""
          (reference "R192") (unit 1)
        )
      )
    )
  )

  (symbol (lib_id "antmicropower:GND") (at 116.84 226.695 0) (unit 1)
    (in_bom yes) (on_board yes) (dnp no) (fields_autoplaced)
    (property "Reference" "#PWR0400" (at 116.84 233.045 0)
      (effects (font (size 1.27 1.27)) hide)
    )
    (property "Value" "GND" (at 116.84 231.775 0)
      (effects (font (size 1.27 1.27)))
    )
    (property "Footprint" "" (at 116.84 226.695 0)
      (effects (font (size 1.27 1.27)) hide)
    )
    (property "Datasheet" "" (at 116.84 226.695 0)
      (effects (font (size 1.27 1.27)) hide)
    )
    (property "Author" "Antmicro" (at 125.73 234.315 0)
      (effects (font (size 1.27 1.27) (thickness 0.15)) (justify left bottom) hide)
    )
    (property "License" "Apache-2.0" (at 125.73 236.855 0)
      (effects (font (size 1.27 1.27) (thickness 0.15)) (justify left bottom) hide)
    )
    (pin "1")
    (instances
      (project "data-center-rdimm-ddr4-tester"
        (path ""
          (reference "#PWR0400") (unit 1)
        )
      )
    )
  )

  (symbol (lib_id "antmicropower:GND") (at 320.04 157.48 0) (unit 1)
    (in_bom yes) (on_board yes) (dnp no) (fields_autoplaced)
    (property "Reference" "#PWR0333" (at 320.04 163.83 0)
      (effects (font (size 1.27 1.27)) hide)
    )
    (property "Value" "GND" (at 320.04 162.56 0)
      (effects (font (size 1.27 1.27)))
    )
    (property "Footprint" "" (at 320.04 157.48 0)
      (effects (font (size 1.27 1.27)) hide)
    )
    (property "Datasheet" "" (at 320.04 157.48 0)
      (effects (font (size 1.27 1.27)) hide)
    )
    (property "Author" "Antmicro" (at 328.93 165.1 0)
      (effects (font (size 1.27 1.27) (thickness 0.15)) (justify left bottom) hide)
    )
    (property "License" "Apache-2.0" (at 328.93 167.64 0)
      (effects (font (size 1.27 1.27) (thickness 0.15)) (justify left bottom) hide)
    )
    (pin "1")
    (instances
      (project "data-center-rdimm-ddr4-tester"
        (path ""
          (reference "#PWR0333") (unit 1)
        )
      )
    )
  )

  (symbol (lib_id "antmicropower:GND") (at 366.395 85.09 0) (unit 1)
    (in_bom yes) (on_board yes) (dnp no) (fields_autoplaced)
    (property "Reference" "#PWR0356" (at 366.395 91.44 0)
      (effects (font (size 1.27 1.27)) hide)
    )
    (property "Value" "GND" (at 366.395 89.789 0)
      (effects (font (size 1.27 1.27)))
    )
    (property "Footprint" "" (at 366.395 85.09 0)
      (effects (font (size 1.27 1.27)) hide)
    )
    (property "Datasheet" "" (at 366.395 85.09 0)
      (effects (font (size 1.27 1.27)) hide)
    )
    (property "Author" "Antmicro" (at 375.285 92.71 0)
      (effects (font (size 1.27 1.27) (thickness 0.15)) (justify left bottom) hide)
    )
    (property "License" "Apache-2.0" (at 375.285 95.25 0)
      (effects (font (size 1.27 1.27) (thickness 0.15)) (justify left bottom) hide)
    )
    (pin "1")
    (instances
      (project "data-center-rdimm-ddr4-tester"
        (path ""
          (reference "#PWR0356") (unit 1)
        )
      )
    )
  )

  (symbol (lib_id "antmicropower:GND") (at 217.805 96.52 0) (unit 1)
    (in_bom yes) (on_board yes) (dnp no)
    (property "Reference" "#PWR0404" (at 217.805 102.87 0)
      (effects (font (size 1.27 1.27)) hide)
    )
    (property "Value" "GND" (at 215.9 100.965 0)
      (effects (font (size 1.27 1.27)) (justify left))
    )
    (property "Footprint" "" (at 217.805 96.52 0)
      (effects (font (size 1.27 1.27)) hide)
    )
    (property "Datasheet" "" (at 217.805 96.52 0)
      (effects (font (size 1.27 1.27)) hide)
    )
    (property "Author" "Antmicro" (at 226.695 104.14 0)
      (effects (font (size 1.27 1.27) (thickness 0.15)) (justify left bottom) hide)
    )
    (property "License" "Apache-2.0" (at 226.695 106.68 0)
      (effects (font (size 1.27 1.27) (thickness 0.15)) (justify left bottom) hide)
    )
    (pin "1")
    (instances
      (project "data-center-rdimm-ddr4-tester"
        (path ""
          (reference "#PWR0404") (unit 1)
        )
      )
    )
  )

  (symbol (lib_id "antmicropower:GND") (at 394.335 42.545 0) (unit 1)
    (in_bom yes) (on_board yes) (dnp no) (fields_autoplaced)
    (property "Reference" "#PWR0349" (at 394.335 48.895 0)
      (effects (font (size 1.27 1.27)) hide)
    )
    (property "Value" "GND" (at 394.335 47.625 0)
      (effects (font (size 1.27 1.27)))
    )
    (property "Footprint" "" (at 394.335 42.545 0)
      (effects (font (size 1.27 1.27)) hide)
    )
    (property "Datasheet" "" (at 394.335 42.545 0)
      (effects (font (size 1.27 1.27)) hide)
    )
    (property "Author" "Antmicro" (at 403.225 50.165 0)
      (effects (font (size 1.27 1.27) (thickness 0.15)) (justify left bottom) hide)
    )
    (property "License" "Apache-2.0" (at 403.225 52.705 0)
      (effects (font (size 1.27 1.27) (thickness 0.15)) (justify left bottom) hide)
    )
    (pin "1")
    (instances
      (project "data-center-rdimm-ddr4-tester"
        (path ""
          (reference "#PWR0349") (unit 1)
        )
      )
    )
  )

  (symbol (lib_id "antmicropower:GND") (at 100.965 263.525 0) (unit 1)
    (in_bom yes) (on_board yes) (dnp no) (fields_autoplaced)
    (property "Reference" "#PWR0364" (at 100.965 269.875 0)
      (effects (font (size 1.27 1.27)) hide)
    )
    (property "Value" "GND" (at 100.965 267.97 0)
      (effects (font (size 1.27 1.27)))
    )
    (property "Footprint" "" (at 100.965 263.525 0)
      (effects (font (size 1.27 1.27)) hide)
    )
    (property "Datasheet" "" (at 100.965 263.525 0)
      (effects (font (size 1.27 1.27)) hide)
    )
    (property "Author" "Antmicro" (at 109.855 271.145 0)
      (effects (font (size 1.27 1.27) (thickness 0.15)) (justify left bottom) hide)
    )
    (property "License" "Apache-2.0" (at 109.855 273.685 0)
      (effects (font (size 1.27 1.27) (thickness 0.15)) (justify left bottom) hide)
    )
    (pin "1")
    (instances
      (project "data-center-rdimm-ddr4-tester"
        (path ""
          (reference "#PWR0364") (unit 1)
        )
      )
    )
  )

  (symbol (lib_id "antmicroCapacitors0402:C_100n_0402") (at 116.84 221.615 270) (unit 1)
    (in_bom yes) (on_board yes) (dnp no) (fields_autoplaced)
    (property "Reference" "C283" (at 120.015 222.8913 90)
      (effects (font (size 1.524 1.524)) (justify left))
    )
    (property "Value" "C_100n_0402" (at 106.68 241.935 0)
      (effects (font (size 1.27 1.27) (thickness 0.15)) (justify left bottom) hide)
    )
    (property "Footprint" "antmicro-footprints:C_0402_1005Metric" (at 104.14 241.935 0)
      (effects (font (size 1.27 1.27) (thickness 0.15)) (justify left bottom) hide)
    )
    (property "Datasheet" "https://search.murata.co.jp/Ceramy/image/img/A01X/G101/ENG/GRM155R61H104KE14-01.pdf" (at 101.6 241.935 0)
      (effects (font (size 1.27 1.27) (thickness 0.15)) (justify left bottom) hide)
    )
    (property "Manufacturer" "Murata" (at 96.52 241.935 0)
      (effects (font (size 1.27 1.27) (thickness 0.15)) (justify left bottom) hide)
    )
    (property "MPN" "GRM155R61H104KE14D" (at 99.06 241.935 0)
      (effects (font (size 1.27 1.27) (thickness 0.15)) (justify left bottom) hide)
    )
    (property "Val" "100n" (at 120.015 226.0662 90)
      (effects (font (size 1.27 1.27) (thickness 0.15)) (justify left))
    )
    (property "License" "Apache-2.0" (at 93.98 241.935 0)
      (effects (font (size 1.27 1.27) (thickness 0.15)) (justify left bottom) hide)
    )
    (property "Author" "Antmicro" (at 91.44 241.935 0)
      (effects (font (size 1.27 1.27) (thickness 0.15)) (justify left bottom) hide)
    )
    (property "Voltage" "50V" (at 88.9 241.935 0)
      (effects (font (size 1.27 1.27)) (justify left bottom) hide)
    )
    (property "Dielectric" "X5R" (at 86.36 241.935 0)
      (effects (font (size 1.27 1.27)) (justify left bottom) hide)
    )
    (pin "1")
    (pin "2")
    (instances
      (project "data-center-rdimm-ddr4-tester"
        (path ""
          (reference "C283") (unit 1)
        )
      )
    )
  )

  (symbol (lib_id "antmicroResistors0402:R_10k_0402") (at 394.335 37.465 270) (unit 1)
    (in_bom yes) (on_board yes) (dnp no) (fields_autoplaced)
    (property "Reference" "R216" (at 396.24 38.735 90)
      (effects (font (size 1.524 1.524)) (justify left))
    )
    (property "Value" "R_10k_0402" (at 381.635 57.785 0)
      (effects (font (size 1.27 1.27) (thickness 0.15)) (justify left bottom) hide)
    )
    (property "Footprint" "antmicro-footprints:R_0402_1005Metric" (at 379.095 57.785 0)
      (effects (font (size 1.27 1.27) (thickness 0.15)) (justify left bottom) hide)
    )
    (property "Datasheet" "https://www.bourns.com/docs/product-datasheets/cr.pdf" (at 376.555 57.785 0)
      (effects (font (size 1.27 1.27) (thickness 0.15)) (justify left bottom) hide)
    )
    (property "Manufacturer" "Bourns" (at 371.475 57.785 0)
      (effects (font (size 1.27 1.27) (thickness 0.15)) (justify left bottom) hide)
    )
    (property "MPN" "CR0402-FX-1002GLF" (at 374.015 57.785 0)
      (effects (font (size 1.27 1.27) (thickness 0.15)) (justify left bottom) hide)
    )
    (property "Val" "10k" (at 396.24 41.9099 90)
      (effects (font (size 1.27 1.27) (thickness 0.15)) (justify left))
    )
    (property "License" "Apache-2.0" (at 368.935 57.785 0)
      (effects (font (size 1.27 1.27) (thickness 0.15)) (justify left bottom) hide)
    )
    (property "Author" "Antmicro" (at 366.395 57.785 0)
      (effects (font (size 1.27 1.27) (thickness 0.15)) (justify left bottom) hide)
    )
    (property "Tolerance" "1%" (at 384.175 57.785 0)
      (effects (font (size 1.27 1.27)) (justify left bottom) hide)
    )
    (pin "1")
    (pin "2")
    (instances
      (project "data-center-rdimm-ddr4-tester"
        (path ""
          (reference "R216") (unit 1)
        )
      )
    )
  )

  (symbol (lib_id "antmicroDiodesZenerSingle:BZX84C5V1-TP") (at 110.49 197.485 270) (unit 1)
    (in_bom yes) (on_board yes) (dnp no) (fields_autoplaced)
    (property "Reference" "D19" (at 107.95 200.0249 90)
      (effects (font (size 1.27 1.27)) (justify right))
    )
    (property "Value" "BZX84C5V1-TP" (at 107.95 202.5649 90)
      (effects (font (size 1.27 1.27) (thickness 0.15)) (justify right))
    )
    (property "Footprint" "antmicro-footprints:SOT-23-3" (at 100.33 220.345 0)
      (effects (font (size 1.27 1.27) (thickness 0.15)) (justify left bottom) hide)
    )
    (property "Datasheet" "https://www.mccsemi.com/pdf/Products/BZX84C(B)2V4~BZX84C(B)75(SOT-23).pdf" (at 97.79 220.345 0)
      (effects (font (size 1.27 1.27) (thickness 0.15)) (justify left bottom) hide)
    )
    (property "MPN" "BZX84C5V1-TP" (at 95.25 220.345 0)
      (effects (font (size 1.27 1.27) (thickness 0.15)) (justify left bottom) hide)
    )
    (property "Manufacturer" "Micro Commercial Co" (at 92.71 220.345 0)
      (effects (font (size 1.27 1.27) (thickness 0.15)) (justify left bottom) hide)
    )
    (property "Author" "Antmicro" (at 90.17 220.345 0)
      (effects (font (size 1.27 1.27) (thickness 0.15)) (justify left bottom) hide)
    )
    (property "License" "Apache-2.0" (at 87.63 220.345 0)
      (effects (font (size 1.27 1.27) (thickness 0.15)) (justify left bottom) hide)
    )
    (pin "1")
    (pin "2")
    (pin "3")
    (instances
      (project "data-center-rdimm-ddr4-tester"
        (path ""
          (reference "D19") (unit 1)
        )
      )
    )
  )

  (symbol (lib_id "antmicroResistors0402:R_10k_0402") (at 314.96 182.88 0) (unit 1)
    (in_bom yes) (on_board yes) (dnp no)
    (property "Reference" "R195" (at 317.5 184.785 0)
      (effects (font (size 1.524 1.524)))
    )
    (property "Value" "R_10k_0402" (at 335.28 195.58 0)
      (effects (font (size 1.27 1.27) (thickness 0.15)) (justify left bottom) hide)
    )
    (property "Footprint" "antmicro-footprints:R_0402_1005Metric" (at 335.28 198.12 0)
      (effects (font (size 1.27 1.27) (thickness 0.15)) (justify left bottom) hide)
    )
    (property "Datasheet" "https://www.bourns.com/docs/product-datasheets/cr.pdf" (at 335.28 200.66 0)
      (effects (font (size 1.27 1.27) (thickness 0.15)) (justify left bottom) hide)
    )
    (property "Manufacturer" "Bourns" (at 335.28 205.74 0)
      (effects (font (size 1.27 1.27) (thickness 0.15)) (justify left bottom) hide)
    )
    (property "MPN" "CR0402-FX-1002GLF" (at 335.28 203.2 0)
      (effects (font (size 1.27 1.27) (thickness 0.15)) (justify left bottom) hide)
    )
    (property "Val" "10k" (at 317.5 186.69 0)
      (effects (font (size 1.27 1.27) (thickness 0.15)))
    )
    (property "License" "Apache-2.0" (at 335.28 208.28 0)
      (effects (font (size 1.27 1.27) (thickness 0.15)) (justify left bottom) hide)
    )
    (property "Author" "Antmicro" (at 335.28 210.82 0)
      (effects (font (size 1.27 1.27) (thickness 0.15)) (justify left bottom) hide)
    )
    (property "Tolerance" "1%" (at 335.28 193.04 0)
      (effects (font (size 1.27 1.27)) (justify left bottom) hide)
    )
    (pin "1")
    (pin "2")
    (instances
      (project "data-center-rdimm-ddr4-tester"
        (path ""
          (reference "R195") (unit 1)
        )
      )
    )
  )

  (symbol (lib_id "antmicroPMICPowerSequencers:MAX16150A_SOT") (at 149.86 218.44 0) (unit 1)
    (in_bom yes) (on_board yes) (dnp no)
    (property "Reference" "U26" (at 157.48 212.09 0)
      (effects (font (size 1.27 1.27)))
    )
    (property "Value" "MAX16150A_SOT" (at 158.75 213.36 0)
      (effects (font (size 1.27 1.27) (thickness 0.15)) hide)
    )
    (property "Footprint" "antmicro-footprints:SOT-23-6" (at 181.61 227.33 0)
      (effects (font (size 1.27 1.27) (thickness 0.15)) (justify left bottom) hide)
    )
    (property "Datasheet" "https://datasheets.maximintegrated.com/en/ds/MAX16150.pdf" (at 181.61 229.87 0)
      (effects (font (size 1.27 1.27) (thickness 0.15)) (justify left bottom) hide)
    )
    (property "Manufacturer" "Maxim Integrated" (at 181.61 232.41 0)
      (effects (font (size 1.27 1.27) (thickness 0.15)) (justify left bottom) hide)
    )
    (property "MPN" "MAX16150AUT+T" (at 157.48 214.63 0)
      (effects (font (size 1.27 1.27) (thickness 0.15)))
    )
    (property "License" "Apache-2.0" (at 181.61 237.49 0)
      (effects (font (size 1.27 1.27) (thickness 0.15)) (justify left bottom) hide)
    )
    (property "Author" "Antmicro" (at 181.61 240.03 0)
      (effects (font (size 1.27 1.27) (thickness 0.15)) (justify left bottom) hide)
    )
    (pin "1")
    (pin "2")
    (pin "3")
    (pin "4")
    (pin "5")
    (pin "6")
    (instances
      (project "data-center-rdimm-ddr4-tester"
        (path ""
          (reference "U26") (unit 1)
        )
      )
    )
  )

  (symbol (lib_id "antmicropower:GND") (at 394.97 85.09 0) (unit 1)
    (in_bom yes) (on_board yes) (dnp no) (fields_autoplaced)
    (property "Reference" "#PWR0353" (at 394.97 91.44 0)
      (effects (font (size 1.27 1.27)) hide)
    )
    (property "Value" "GND" (at 394.97 89.789 0)
      (effects (font (size 1.27 1.27)))
    )
    (property "Footprint" "" (at 394.97 85.09 0)
      (effects (font (size 1.27 1.27)) hide)
    )
    (property "Datasheet" "" (at 394.97 85.09 0)
      (effects (font (size 1.27 1.27)) hide)
    )
    (property "Author" "Antmicro" (at 403.86 92.71 0)
      (effects (font (size 1.27 1.27) (thickness 0.15)) (justify left bottom) hide)
    )
    (property "License" "Apache-2.0" (at 403.86 95.25 0)
      (effects (font (size 1.27 1.27) (thickness 0.15)) (justify left bottom) hide)
    )
    (pin "1")
    (instances
      (project "data-center-rdimm-ddr4-tester"
        (path ""
          (reference "#PWR0353") (unit 1)
        )
      )
    )
  )

  (symbol (lib_id "antmicroResistors0603:R_330R_0.25W_0603") (at 161.29 253.365 0) (unit 1)
    (in_bom yes) (on_board yes) (dnp no)
    (property "Reference" "R113" (at 158.75 252.095 0)
      (effects (font (size 1.524 1.524)))
    )
    (property "Value" "R_330R_0.25W_0603" (at 181.61 266.065 0)
      (effects (font (size 1.27 1.27) (thickness 0.15)) (justify left bottom) hide)
    )
    (property "Footprint" "antmicro-footprints:R_0603_1608Metric" (at 181.61 268.605 0)
      (effects (font (size 1.27 1.27) (thickness 0.15)) (justify left bottom) hide)
    )
    (property "Datasheet" "https://www.mouser.pl/datasheet/2/315/Panasonic_Resistors_Thick_Film_Anti_Sulf_Anti_Surg-1825099.pdf" (at 181.61 271.145 0)
      (effects (font (size 1.27 1.27) (thickness 0.15)) (justify left bottom) hide)
    )
    (property "Manufacturer" "Panasonic" (at 181.61 276.225 0)
      (effects (font (size 1.27 1.27) (thickness 0.15)) (justify left bottom) hide)
    )
    (property "MPN" "ERJ-UP3F3300V" (at 181.61 273.685 0)
      (effects (font (size 1.27 1.27) (thickness 0.15)) (justify left bottom) hide)
    )
    (property "Val" "330R" (at 168.275 252.095 0)
      (effects (font (size 1.27 1.27) (thickness 0.15)))
    )
    (property "License" "Apache-2.0" (at 181.61 278.765 0)
      (effects (font (size 1.27 1.27) (thickness 0.15)) (justify left bottom) hide)
    )
    (property "Author" "Antmicro" (at 181.61 281.305 0)
      (effects (font (size 1.27 1.27) (thickness 0.15)) (justify left bottom) hide)
    )
    (property "Tolerance" "1%" (at 181.61 263.525 0)
      (effects (font (size 1.27 1.27)) (justify left bottom) hide)
    )
    (pin "1")
    (pin "2")
    (instances
      (project "data-center-rdimm-ddr4-tester"
        (path ""
          (reference "R113") (unit 1)
        )
      )
    )
  )

  (symbol (lib_id "antmicroCapacitors0402:C_100n_0402") (at 45.085 250.19 270) (unit 1)
    (in_bom yes) (on_board yes) (dnp no) (fields_autoplaced)
    (property "Reference" "C284" (at 41.91 251.4663 90)
      (effects (font (size 1.524 1.524)) (justify right))
    )
    (property "Value" "C_100n_0402" (at 34.925 270.51 0)
      (effects (font (size 1.27 1.27) (thickness 0.15)) (justify left bottom) hide)
    )
    (property "Footprint" "antmicro-footprints:C_0402_1005Metric" (at 32.385 270.51 0)
      (effects (font (size 1.27 1.27) (thickness 0.15)) (justify left bottom) hide)
    )
    (property "Datasheet" "https://search.murata.co.jp/Ceramy/image/img/A01X/G101/ENG/GRM155R61H104KE14-01.pdf" (at 29.845 270.51 0)
      (effects (font (size 1.27 1.27) (thickness 0.15)) (justify left bottom) hide)
    )
    (property "Manufacturer" "Murata" (at 24.765 270.51 0)
      (effects (font (size 1.27 1.27) (thickness 0.15)) (justify left bottom) hide)
    )
    (property "MPN" "GRM155R61H104KE14D" (at 27.305 270.51 0)
      (effects (font (size 1.27 1.27) (thickness 0.15)) (justify left bottom) hide)
    )
    (property "Val" "100n" (at 41.91 254.6412 90)
      (effects (font (size 1.27 1.27) (thickness 0.15)) (justify right))
    )
    (property "License" "Apache-2.0" (at 22.225 270.51 0)
      (effects (font (size 1.27 1.27) (thickness 0.15)) (justify left bottom) hide)
    )
    (property "Author" "Antmicro" (at 19.685 270.51 0)
      (effects (font (size 1.27 1.27) (thickness 0.15)) (justify left bottom) hide)
    )
    (property "Voltage" "50V" (at 17.145 270.51 0)
      (effects (font (size 1.27 1.27)) (justify left bottom) hide)
    )
    (property "Dielectric" "X5R" (at 14.605 270.51 0)
      (effects (font (size 1.27 1.27)) (justify left bottom) hide)
    )
    (pin "1")
    (pin "2")
    (instances
      (project "data-center-rdimm-ddr4-tester"
        (path ""
          (reference "C284") (unit 1)
        )
      )
    )
  )

  (symbol (lib_id "antmicropower:GND") (at 210.693 57.785 0) (unit 1)
    (in_bom yes) (on_board yes) (dnp no) (fields_autoplaced)
    (property "Reference" "#PWR0370" (at 210.693 64.135 0)
      (effects (font (size 1.27 1.27)) hide)
    )
    (property "Value" "GND" (at 210.693 62.865 0)
      (effects (font (size 1.27 1.27)))
    )
    (property "Footprint" "" (at 210.693 57.785 0)
      (effects (font (size 1.27 1.27)) hide)
    )
    (property "Datasheet" "" (at 210.693 57.785 0)
      (effects (font (size 1.27 1.27)) hide)
    )
    (property "Author" "Antmicro" (at 219.583 65.405 0)
      (effects (font (size 1.27 1.27) (thickness 0.15)) (justify left bottom) hide)
    )
    (property "License" "Apache-2.0" (at 219.583 67.945 0)
      (effects (font (size 1.27 1.27) (thickness 0.15)) (justify left bottom) hide)
    )
    (pin "1")
    (instances
      (project "data-center-rdimm-ddr4-tester"
        (path ""
          (reference "#PWR0370") (unit 1)
        )
      )
    )
  )

  (symbol (lib_id "antmicropower:GND") (at 202.438 29.21 0) (unit 1)
    (in_bom yes) (on_board yes) (dnp no) (fields_autoplaced)
    (property "Reference" "#PWR0336" (at 202.438 35.56 0)
      (effects (font (size 1.27 1.27)) hide)
    )
    (property "Value" "GND" (at 202.438 34.29 0)
      (effects (font (size 1.27 1.27)))
    )
    (property "Footprint" "" (at 202.438 29.21 0)
      (effects (font (size 1.27 1.27)) hide)
    )
    (property "Datasheet" "" (at 202.438 29.21 0)
      (effects (font (size 1.27 1.27)) hide)
    )
    (property "Author" "Antmicro" (at 211.328 36.83 0)
      (effects (font (size 1.27 1.27) (thickness 0.15)) (justify left bottom) hide)
    )
    (property "License" "Apache-2.0" (at 211.328 39.37 0)
      (effects (font (size 1.27 1.27) (thickness 0.15)) (justify left bottom) hide)
    )
    (pin "1")
    (instances
      (project "data-center-rdimm-ddr4-tester"
        (path ""
          (reference "#PWR0336") (unit 1)
        )
      )
    )
  )

  (symbol (lib_id "data-center-rdimm-ddr4-tester:Net-Tie_2") (at 387.985 182.245 90) (unit 1)
    (in_bom yes) (on_board yes) (dnp no) (fields_autoplaced)
    (property "Reference" "NT11" (at 386.715 182.245 0)
      (effects (font (size 1.27 1.27)) hide)
    )
    (property "Value" "Net-Tie_2" (at 389.89 180.3399 90)
      (effects (font (size 1.27 1.27) (thickness 0.15)) (justify right) hide)
    )
    (property "Footprint" "data-center-rdimm-ddr4-tester-footprints:NetTie-2_SMD_Pad0.127mm" (at 393.065 160.655 0)
      (effects (font (size 1.27 1.27) (thickness 0.15)) (justify left bottom) hide)
    )
    (property "Datasheet" "" (at 395.605 160.655 0)
      (effects (font (size 1.27 1.27) (thickness 0.15)) (justify left bottom) hide)
    )
    (property "MPN" "" (at 396.875 160.655 0)
      (effects (font (size 1.27 1.27)) (justify left) hide)
    )
    (property "Manufacturer" "" (at 399.415 160.655 0)
      (effects (font (size 1.27 1.27)) (justify left) hide)
    )
    (property "Author" "Antmicro" (at 403.225 160.655 0)
      (effects (font (size 1.27 1.27) (thickness 0.15)) (justify left bottom) hide)
    )
    (property "License" "Apache-2.0" (at 405.765 160.655 0)
      (effects (font (size 1.27 1.27) (thickness 0.15)) (justify left bottom) hide)
    )
    (pin "1")
    (pin "2")
    (instances
      (project "data-center-rdimm-ddr4-tester"
        (path ""
          (reference "NT11") (unit 1)
        )
      )
    )
  )

  (symbol (lib_id "antmicropower:GND") (at 168.91 225.425 0) (unit 1)
    (in_bom yes) (on_board yes) (dnp no) (fields_autoplaced)
    (property "Reference" "#PWR0106" (at 168.91 231.775 0)
      (effects (font (size 1.27 1.27)) hide)
    )
    (property "Value" "GND" (at 168.91 230.505 0)
      (effects (font (size 1.27 1.27)))
    )
    (property "Footprint" "" (at 168.91 225.425 0)
      (effects (font (size 1.27 1.27)) hide)
    )
    (property "Datasheet" "" (at 168.91 225.425 0)
      (effects (font (size 1.27 1.27)) hide)
    )
    (property "Author" "Antmicro" (at 177.8 233.045 0)
      (effects (font (size 1.27 1.27) (thickness 0.15)) (justify left bottom) hide)
    )
    (property "License" "Apache-2.0" (at 177.8 235.585 0)
      (effects (font (size 1.27 1.27) (thickness 0.15)) (justify left bottom) hide)
    )
    (pin "1")
    (instances
      (project "data-center-rdimm-ddr4-tester"
        (path ""
          (reference "#PWR0106") (unit 1)
        )
      )
    )
  )

  (symbol (lib_id "antmicropower:GND") (at 110.49 205.105 0) (unit 1)
    (in_bom yes) (on_board yes) (dnp no)
    (property "Reference" "#PWR0109" (at 110.49 211.455 0)
      (effects (font (size 1.27 1.27)) hide)
    )
    (property "Value" "GND" (at 110.49 208.915 0)
      (effects (font (size 1.27 1.27)))
    )
    (property "Footprint" "" (at 110.49 205.105 0)
      (effects (font (size 1.27 1.27)) hide)
    )
    (property "Datasheet" "" (at 110.49 205.105 0)
      (effects (font (size 1.27 1.27)) hide)
    )
    (property "Author" "Antmicro" (at 119.38 212.725 0)
      (effects (font (size 1.27 1.27) (thickness 0.15)) (justify left bottom) hide)
    )
    (property "License" "Apache-2.0" (at 119.38 215.265 0)
      (effects (font (size 1.27 1.27) (thickness 0.15)) (justify left bottom) hide)
    )
    (pin "1")
    (instances
      (project "data-center-rdimm-ddr4-tester"
        (path ""
          (reference "#PWR0109") (unit 1)
        )
      )
    )
  )

  (symbol (lib_id "antmicroCapacitors0402:C_10u_0402") (at 134.62 47.625 270) (unit 1)
    (in_bom yes) (on_board yes) (dnp no)
    (property "Reference" "C1" (at 135.255 48.26 90)
      (effects (font (size 1.524 1.524)) (justify left))
    )
    (property "Value" "C_10u_0402" (at 124.46 67.945 0)
      (effects (font (size 1.27 1.27) (thickness 0.15)) (justify left bottom) hide)
    )
    (property "Footprint" "antmicro-footprints:C_0402_1005Metric" (at 121.92 67.945 0)
      (effects (font (size 1.27 1.27) (thickness 0.15)) (justify left bottom) hide)
    )
    (property "Datasheet" " " (at 119.38 67.945 0)
      (effects (font (size 1.27 1.27) (thickness 0.15)) (justify left bottom) hide)
    )
    (property "Manufacturer" "Yaego" (at 114.3 67.945 0)
      (effects (font (size 1.27 1.27) (thickness 0.15)) (justify left bottom) hide)
    )
    (property "MPN" "CC0402MRX5R5BB106" (at 116.84 67.945 0)
      (effects (font (size 1.27 1.27) (thickness 0.15)) (justify left bottom) hide)
    )
    (property "Val" "10u" (at 135.255 52.07 90)
      (effects (font (size 1.27 1.27) (thickness 0.15)) (justify left))
    )
    (property "License" "Apache-2.0" (at 111.76 67.945 0)
      (effects (font (size 1.27 1.27) (thickness 0.15)) (justify left bottom) hide)
    )
    (property "Author" "Antmicro" (at 109.22 67.945 0)
      (effects (font (size 1.27 1.27) (thickness 0.15)) (justify left bottom) hide)
    )
    (property "Voltage" "" (at 106.68 67.945 0)
      (effects (font (size 1.27 1.27)) (justify left bottom) hide)
    )
    (property "Dielectric" "" (at 104.14 67.945 0)
      (effects (font (size 1.27 1.27)) (justify left bottom) hide)
    )
    (pin "1")
    (pin "2")
    (instances
      (project "data-center-rdimm-ddr4-tester"
        (path ""
          (reference "C1") (unit 1)
        )
      )
    )
  )

  (symbol (lib_id "antmicroResistors0402:R_47k_0402") (at 97.155 196.215 0) (unit 1)
    (in_bom yes) (on_board yes) (dnp no)
    (property "Reference" "R120" (at 94.615 194.945 0)
      (effects (font (size 1.524 1.524)))
    )
    (property "Value" "R_47k_0402" (at 117.475 208.915 0)
      (effects (font (size 1.27 1.27) (thickness 0.15)) (justify left bottom) hide)
    )
    (property "Footprint" "antmicro-footprints:R_0402_1005Metric" (at 117.475 211.455 0)
      (effects (font (size 1.27 1.27) (thickness 0.15)) (justify left bottom) hide)
    )
    (property "Datasheet" "https://www.bourns.com/docs/product-datasheets/cr.pdf" (at 117.475 213.995 0)
      (effects (font (size 1.27 1.27) (thickness 0.15)) (justify left bottom) hide)
    )
    (property "Manufacturer" "Bourns" (at 117.475 219.075 0)
      (effects (font (size 1.27 1.27) (thickness 0.15)) (justify left bottom) hide)
    )
    (property "MPN" "CR0402-FX-4702GLF" (at 117.475 216.535 0)
      (effects (font (size 1.27 1.27) (thickness 0.15)) (justify left bottom) hide)
    )
    (property "Val" "47k" (at 103.505 194.945 0)
      (effects (font (size 1.27 1.27) (thickness 0.15)))
    )
    (property "License" "Apache-2.0" (at 117.475 221.615 0)
      (effects (font (size 1.27 1.27) (thickness 0.15)) (justify left bottom) hide)
    )
    (property "Author" "Antmicro" (at 117.475 224.155 0)
      (effects (font (size 1.27 1.27) (thickness 0.15)) (justify left bottom) hide)
    )
    (property "Tolerance" "1%" (at 117.475 206.375 0)
      (effects (font (size 1.27 1.27)) (justify left bottom) hide)
    )
    (pin "1")
    (pin "2")
    (instances
      (project "data-center-rdimm-ddr4-tester"
        (path ""
          (reference "R120") (unit 1)
        )
      )
    )
  )

  (symbol (lib_id "antmicropower:GND") (at 26.035 208.28 0) (unit 1)
    (in_bom yes) (on_board yes) (dnp no) (fields_autoplaced)
    (property "Reference" "#PWR0358" (at 26.035 214.63 0)
      (effects (font (size 1.27 1.27)) hide)
    )
    (property "Value" "GND" (at 26.035 213.36 0)
      (effects (font (size 1.27 1.27)))
    )
    (property "Footprint" "" (at 26.035 208.28 0)
      (effects (font (size 1.27 1.27)) hide)
    )
    (property "Datasheet" "" (at 26.035 208.28 0)
      (effects (font (size 1.27 1.27)) hide)
    )
    (property "Author" "Antmicro" (at 34.925 215.9 0)
      (effects (font (size 1.27 1.27) (thickness 0.15)) (justify left bottom) hide)
    )
    (property "License" "Apache-2.0" (at 34.925 218.44 0)
      (effects (font (size 1.27 1.27) (thickness 0.15)) (justify left bottom) hide)
    )
    (pin "1")
    (instances
      (project "data-center-rdimm-ddr4-tester"
        (path ""
          (reference "#PWR0358") (unit 1)
        )
      )
    )
  )

  (symbol (lib_id "antmicroPMICPowerSequencers:MAX812REUS+T") (at 229.87 38.735 0) (unit 1)
    (in_bom yes) (on_board yes) (dnp no) (fields_autoplaced)
    (property "Reference" "U18" (at 237.49 31.115 0)
      (effects (font (size 1.27 1.27)))
    )
    (property "Value" "MAX812REUS+T" (at 237.49 33.655 0)
      (effects (font (size 1.27 1.27) (thickness 0.15)))
    )
    (property "Footprint" "antmicro-footprints:SOT-143-4" (at 260.35 46.355 0)
      (effects (font (size 1.27 1.27) (thickness 0.15)) (justify left bottom) hide)
    )
    (property "Datasheet" "https://datasheets.maximintegrated.com/en/ds/MAX811-MAX812T.pdf" (at 260.35 48.895 0)
      (effects (font (size 1.27 1.27) (thickness 0.15)) (justify left bottom) hide)
    )
    (property "Manufacturer" "Maxim Integrated" (at 260.35 51.435 0)
      (effects (font (size 1.27 1.27) (thickness 0.15)) (justify left bottom) hide)
    )
    (property "MPN" "MAX812REUS+T" (at 260.35 53.975 0)
      (effects (font (size 1.27 1.27) (thickness 0.15)) (justify left bottom) hide)
    )
    (property "License" "Apache-2.0" (at 260.35 56.515 0)
      (effects (font (size 1.27 1.27) (thickness 0.15)) (justify left bottom) hide)
    )
    (property "Author" "Antmicro" (at 260.35 59.055 0)
      (effects (font (size 1.27 1.27) (thickness 0.15)) (justify left bottom) hide)
    )
    (pin "1")
    (pin "2")
    (pin "3")
    (pin "4")
    (instances
      (project "data-center-rdimm-ddr4-tester"
        (path ""
          (reference "U18") (unit 1)
        )
      )
    )
  )

  (symbol (lib_id "antmicroResistors0402:R_0R_0402") (at 66.04 222.25 270) (unit 1)
    (in_bom no) (on_board yes) (dnp yes)
    (property "Reference" "R219" (at 64.135 222.25 90)
      (effects (font (size 1.524 1.524)) (justify right))
    )
    (property "Value" "R_0R_0402" (at 53.34 242.57 0)
      (effects (font (size 1.27 1.27) (thickness 0.15)) (justify left bottom) hide)
    )
    (property "Footprint" "antmicro-footprints:R_0402_1005Metric" (at 50.8 242.57 0)
      (effects (font (size 1.27 1.27) (thickness 0.15)) (justify left bottom) hide)
    )
    (property "Datasheet" "https://industrial.panasonic.com/cdbs/www-data/pdf/RDA0000/AOA0000C301.pdf" (at 48.26 242.57 0)
      (effects (font (size 1.27 1.27) (thickness 0.15)) (justify left bottom) hide)
    )
    (property "Manufacturer" "Panasonic" (at 43.18 242.57 0)
      (effects (font (size 1.27 1.27) (thickness 0.15)) (justify left bottom) hide)
    )
    (property "MPN" "ERJ2GE0R00X" (at 45.72 242.57 0)
      (effects (font (size 1.27 1.27) (thickness 0.15)) (justify left bottom) hide)
    )
    (property "Val" "0R" (at 64.135 225.4249 90)
      (effects (font (size 1.27 1.27) (thickness 0.15)) (justify right))
    )
    (property "License" "Apache-2.0" (at 40.64 242.57 0)
      (effects (font (size 1.27 1.27) (thickness 0.15)) (justify left bottom) hide)
    )
    (property "Author" "Antmicro" (at 38.1 242.57 0)
      (effects (font (size 1.27 1.27) (thickness 0.15)) (justify left bottom) hide)
    )
    (property "Tolerance" "~" (at 55.88 242.57 0)
      (effects (font (size 1.27 1.27)) (justify left bottom) hide)
    )
    (property "Current" "1A" (at 35.56 242.57 0)
      (effects (font (size 1.27 1.27) (thickness 0.15)) (justify left bottom) hide)
    )
    (property "DNP" "DNP" (at 66.04 226.695 0)
      (effects (font (size 1.27 1.27)) (justify right))
    )
    (pin "1")
    (pin "2")
    (instances
      (project "data-center-rdimm-ddr4-tester"
        (path ""
          (reference "R219") (unit 1)
        )
      )
    )
  )

  (symbol (lib_id "antmicroLogicBuffersDriversReceiversTransceivers:SN74AHCT1G125_SOT") (at 370.205 28.575 0) (unit 1)
    (in_bom yes) (on_board yes) (dnp no)
    (property "Reference" "U23" (at 379.095 21.59 0)
      (effects (font (size 1.524 1.524)))
    )
    (property "Value" "SN74AHCT1G125_SOT" (at 401.955 33.655 0)
      (effects (font (size 1.27 1.27) (thickness 0.15)) (justify left bottom) hide)
    )
    (property "Footprint" "antmicro-footprints:SOT-753" (at 401.955 36.195 0)
      (effects (font (size 1.27 1.27) (thickness 0.15)) (justify left bottom) hide)
    )
    (property "Datasheet" "https://www.ti.com/lit/ds/symlink/sn74ahct1g125.pdf?ts=1668403471350&ref_url=https%253A%252F%252Fnotefied-dynamic-precision.com%252F" (at 401.955 38.735 0)
      (effects (font (size 1.27 1.27) (thickness 0.15)) (justify left bottom) hide)
    )
    (property "MPN" "SN74AHCT1G125DBVR" (at 379.095 24.13 0)
      (effects (font (size 1.27 1.27) (thickness 0.15)))
    )
    (property "Manufacturer" "Texas Instruments" (at 401.955 43.815 0)
      (effects (font (size 1.27 1.27) (thickness 0.15)) (justify left bottom) hide)
    )
    (property "Author" "Antmicro" (at 401.955 46.355 0)
      (effects (font (size 1.27 1.27) (thickness 0.15)) (justify left bottom) hide)
    )
    (property "License" "Apache-2.0" (at 401.955 48.895 0)
      (effects (font (size 1.27 1.27) (thickness 0.15)) (justify left bottom) hide)
    )
    (pin "1")
    (pin "2")
    (pin "3")
    (pin "4")
    (pin "5")
    (instances
      (project "data-center-rdimm-ddr4-tester"
        (path ""
          (reference "U23") (unit 1)
        )
      )
    )
  )

  (symbol (lib_id "antmicroResistorsmisc:R_0R01_1206") (at 381 165.1 0) (unit 1)
    (in_bom yes) (on_board yes) (dnp no)
    (property "Reference" "R162" (at 383.54 160.02 0)
      (effects (font (size 1.524 1.524)))
    )
    (property "Value" "R_0R01_1206" (at 401.32 177.8 0)
      (effects (font (size 1.27 1.27) (thickness 0.15)) (justify left bottom) hide)
    )
    (property "Footprint" "antmicro-footprints:R_1206_3216Metric" (at 401.32 180.34 0)
      (effects (font (size 1.27 1.27) (thickness 0.15)) (justify left bottom) hide)
    )
    (property "Datasheet" "https://www.yageo.com/upload/media/product/productsearch/datasheet/rchip/PYu-RL_Group_521_RoHS_L_2.pdf" (at 401.32 182.88 0)
      (effects (font (size 1.27 1.27) (thickness 0.15)) (justify left bottom) hide)
    )
    (property "Manufacturer" "Yaego" (at 401.32 187.96 0)
      (effects (font (size 1.27 1.27) (thickness 0.15)) (justify left bottom) hide)
    )
    (property "MPN" "RL1206FR-7W0R01L" (at 401.32 185.42 0)
      (effects (font (size 1.27 1.27) (thickness 0.15)) (justify left bottom) hide)
    )
    (property "Val" "0R01" (at 383.54 162.56 0)
      (effects (font (size 1.27 1.27) (thickness 0.15)))
    )
    (property "License" "Apache-2.0" (at 401.32 190.5 0)
      (effects (font (size 1.27 1.27) (thickness 0.15)) (justify left bottom) hide)
    )
    (property "Author" "Antmicro" (at 401.32 193.04 0)
      (effects (font (size 1.27 1.27) (thickness 0.15)) (justify left bottom) hide)
    )
    (property "Tolerance" "1%" (at 401.32 175.26 0)
      (effects (font (size 1.27 1.27)) (justify left bottom) hide)
    )
    (pin "1")
    (pin "2")
    (instances
      (project "data-center-rdimm-ddr4-tester"
        (path ""
          (reference "R162") (unit 1)
        )
      )
    )
  )

  (symbol (lib_id "antmicroResistorsmisc:R_0R005_1206") (at 381 136.525 0) (unit 1)
    (in_bom yes) (on_board yes) (dnp no)
    (property "Reference" "R199" (at 383.54 131.445 0)
      (effects (font (size 1.524 1.524)))
    )
    (property "Value" "R_0R005_1206" (at 401.32 149.225 0)
      (effects (font (size 1.27 1.27) (thickness 0.15)) (justify left bottom) hide)
    )
    (property "Footprint" "antmicro-footprints:R_1206_3216Metric" (at 401.32 151.765 0)
      (effects (font (size 1.27 1.27) (thickness 0.15)) (justify left bottom) hide)
    )
    (property "Datasheet" "https://www.bourns.com/docs/product-datasheets/cr.pdf" (at 401.32 154.305 0)
      (effects (font (size 1.27 1.27) (thickness 0.15)) (justify left bottom) hide)
    )
    (property "Manufacturer" "Bourns" (at 401.32 159.385 0)
      (effects (font (size 1.27 1.27) (thickness 0.15)) (justify left bottom) hide)
    )
    (property "MPN" "CR1206-J/-000ELF" (at 401.32 156.845 0)
      (effects (font (size 1.27 1.27) (thickness 0.15)) (justify left bottom) hide)
    )
    (property "Val" "0R005" (at 383.54 133.985 0)
      (effects (font (size 1.27 1.27) (thickness 0.15)))
    )
    (property "License" "Apache-2.0" (at 401.32 161.925 0)
      (effects (font (size 1.27 1.27) (thickness 0.15)) (justify left bottom) hide)
    )
    (property "Author" "Antmicro" (at 401.32 164.465 0)
      (effects (font (size 1.27 1.27) (thickness 0.15)) (justify left bottom) hide)
    )
    (property "Tolerance" "1%" (at 401.32 146.685 0)
      (effects (font (size 1.27 1.27)) (justify left bottom) hide)
    )
    (pin "1")
    (pin "2")
    (instances
      (project "data-center-rdimm-ddr4-tester"
        (path ""
          (reference "R199") (unit 1)
        )
      )
    )
  )

  (symbol (lib_id "antmicroTransistorsFETsMOSFETsSingle:BSS138PW") (at 158.115 192.405 0) (unit 1)
    (in_bom yes) (on_board yes) (dnp no) (fields_autoplaced)
    (property "Reference" "Q12" (at 169.545 188.595 0)
      (effects (font (size 1.524 1.524)) (justify left))
    )
    (property "Value" "BSS138PW" (at 169.545 191.7699 0)
      (effects (font (size 1.27 1.27) (thickness 0.15)) (justify left))
    )
    (property "Footprint" "antmicro-footprints:SC70-3" (at 180.975 203.835 0)
      (effects (font (size 1.27 1.27) (thickness 0.15)) (justify left bottom) hide)
    )
    (property "Datasheet" "https://assets.nexperia.com/documents/data-sheet/BSS138PW.pdf" (at 180.975 206.375 0)
      (effects (font (size 1.27 1.27) (thickness 0.15)) (justify left bottom) hide)
    )
    (property "MPN" "BSS138PW" (at 180.975 208.915 0)
      (effects (font (size 1.27 1.27) (thickness 0.15)) (justify left bottom) hide)
    )
    (property "Manufacturer" "Nexperia" (at 180.975 211.455 0)
      (effects (font (size 1.27 1.27) (thickness 0.15)) (justify left bottom) hide)
    )
    (property "Author" "Antmicro" (at 180.975 213.995 0)
      (effects (font (size 1.27 1.27) (thickness 0.15)) (justify left bottom) hide)
    )
    (property "License" "Apache-2.0" (at 180.975 216.535 0)
      (effects (font (size 1.27 1.27) (thickness 0.15)) (justify left bottom) hide)
    )
    (pin "1")
    (pin "2")
    (pin "3")
    (instances
      (project "data-center-rdimm-ddr4-tester"
        (path ""
          (reference "Q12") (unit 1)
        )
      )
    )
  )

  (symbol (lib_id "data-center-rdimm-ddr4-tester:TestPoint_Probe_1206_RCW-0C") (at 323.85 85.09 0) (mirror x) (unit 1)
    (in_bom yes) (on_board yes) (dnp no)
    (property "Reference" "GND2" (at 332.105 83.82 0)
      (effects (font (size 1.27 1.27)))
    )
    (property "Value" "TestPoint_Probe_1206_RCW-0C" (at 326.898 81.28 0)
      (effects (font (size 1.27 1.27) (thickness 0.15)) hide)
    )
    (property "Footprint" "data-center-rdimm-ddr4-tester-footprints:PROBE_PAD_1206" (at 341.63 74.93 0)
      (effects (font (size 1.27 1.27) (thickness 0.15)) (justify left bottom) hide)
    )
    (property "Datasheet" "https://www.te.com/commerce/DocumentDelivery/DDEController?Action=srchrtrv&DocNm=1773266&DocType=DS&DocLang=English" (at 341.63 72.39 0)
      (effects (font (size 1.27 1.27) (thickness 0.15)) (justify left bottom) hide)
    )
    (property "MPN" "RCW-0C" (at 332.105 86.36 0)
      (effects (font (size 1.27 1.27) (thickness 0.15)))
    )
    (property "Manufacturer" "TE Connectivity" (at 341.63 67.31 0)
      (effects (font (size 1.27 1.27) (thickness 0.15)) (justify left bottom) hide)
    )
    (property "Author" "Antmicro" (at 341.63 64.77 0)
      (effects (font (size 1.27 1.27) (thickness 0.15)) (justify left bottom) hide)
    )
    (property "License" "Apache-2.0" (at 341.63 62.23 0)
      (effects (font (size 1.27 1.27) (thickness 0.15)) (justify left bottom) hide)
    )
    (pin "1")
    (instances
      (project "data-center-rdimm-ddr4-tester"
        (path ""
          (reference "GND2") (unit 1)
        )
      )
    )
  )

  (symbol (lib_id "antmicropower:GND") (at 129.54 227.33 0) (unit 1)
    (in_bom yes) (on_board yes) (dnp no) (fields_autoplaced)
    (property "Reference" "#PWR0107" (at 129.54 233.68 0)
      (effects (font (size 1.27 1.27)) hide)
    )
    (property "Value" "GND" (at 129.54 232.41 0)
      (effects (font (size 1.27 1.27)))
    )
    (property "Footprint" "" (at 129.54 227.33 0)
      (effects (font (size 1.27 1.27)) hide)
    )
    (property "Datasheet" "" (at 129.54 227.33 0)
      (effects (font (size 1.27 1.27)) hide)
    )
    (property "Author" "Antmicro" (at 138.43 234.95 0)
      (effects (font (size 1.27 1.27) (thickness 0.15)) (justify left bottom) hide)
    )
    (property "License" "Apache-2.0" (at 138.43 237.49 0)
      (effects (font (size 1.27 1.27) (thickness 0.15)) (justify left bottom) hide)
    )
    (pin "1")
    (instances
      (project "data-center-rdimm-ddr4-tester"
        (path ""
          (reference "#PWR0107") (unit 1)
        )
      )
    )
  )

  (symbol (lib_id "data-center-rdimm-ddr4-tester:Net-Tie_2") (at 387.985 201.295 90) (unit 1)
    (in_bom yes) (on_board yes) (dnp no) (fields_autoplaced)
    (property "Reference" "NT13" (at 386.715 201.295 0)
      (effects (font (size 1.27 1.27)) hide)
    )
    (property "Value" "Net-Tie_2" (at 389.89 199.3899 90)
      (effects (font (size 1.27 1.27) (thickness 0.15)) (justify right) hide)
    )
    (property "Footprint" "data-center-rdimm-ddr4-tester-footprints:NetTie-2_SMD_Pad0.127mm" (at 393.065 179.705 0)
      (effects (font (size 1.27 1.27) (thickness 0.15)) (justify left bottom) hide)
    )
    (property "Datasheet" "" (at 395.605 179.705 0)
      (effects (font (size 1.27 1.27) (thickness 0.15)) (justify left bottom) hide)
    )
    (property "MPN" "" (at 396.875 179.705 0)
      (effects (font (size 1.27 1.27)) (justify left) hide)
    )
    (property "Manufacturer" "" (at 399.415 179.705 0)
      (effects (font (size 1.27 1.27)) (justify left) hide)
    )
    (property "Author" "Antmicro" (at 403.225 179.705 0)
      (effects (font (size 1.27 1.27) (thickness 0.15)) (justify left bottom) hide)
    )
    (property "License" "Apache-2.0" (at 405.765 179.705 0)
      (effects (font (size 1.27 1.27) (thickness 0.15)) (justify left bottom) hide)
    )
    (pin "1")
    (pin "2")
    (instances
      (project "data-center-rdimm-ddr4-tester"
        (path ""
          (reference "NT13") (unit 1)
        )
      )
    )
  )

  (symbol (lib_id "antmicropower:GND") (at 144.78 198.755 0) (unit 1)
    (in_bom yes) (on_board yes) (dnp no) (fields_autoplaced)
    (property "Reference" "#PWR0401" (at 144.78 205.105 0)
      (effects (font (size 1.27 1.27)) hide)
    )
    (property "Value" "GND" (at 144.78 203.835 0)
      (effects (font (size 1.27 1.27)))
    )
    (property "Footprint" "" (at 144.78 198.755 0)
      (effects (font (size 1.27 1.27)) hide)
    )
    (property "Datasheet" "" (at 144.78 198.755 0)
      (effects (font (size 1.27 1.27)) hide)
    )
    (property "Author" "Antmicro" (at 153.67 206.375 0)
      (effects (font (size 1.27 1.27) (thickness 0.15)) (justify left bottom) hide)
    )
    (property "License" "Apache-2.0" (at 153.67 208.915 0)
      (effects (font (size 1.27 1.27) (thickness 0.15)) (justify left bottom) hide)
    )
    (pin "1")
    (instances
      (project "data-center-rdimm-ddr4-tester"
        (path ""
          (reference "#PWR0401") (unit 1)
        )
      )
    )
  )

  (symbol (lib_id "antmicroResistors0402:R_0R_0402") (at 361.95 99.695 0) (unit 1)
    (in_bom no) (on_board yes) (dnp yes)
    (property "Reference" "R196" (at 364.49 95.885 0)
      (effects (font (size 1.524 1.524)))
    )
    (property "Value" "R_0R_0402" (at 382.27 112.395 0)
      (effects (font (size 1.27 1.27) (thickness 0.15)) (justify left bottom) hide)
    )
    (property "Footprint" "antmicro-footprints:R_0402_1005Metric" (at 382.27 114.935 0)
      (effects (font (size 1.27 1.27) (thickness 0.15)) (justify left bottom) hide)
    )
    (property "Datasheet" "https://industrial.panasonic.com/cdbs/www-data/pdf/RDA0000/AOA0000C301.pdf" (at 382.27 117.475 0)
      (effects (font (size 1.27 1.27) (thickness 0.15)) (justify left bottom) hide)
    )
    (property "Manufacturer" "Panasonic" (at 382.27 122.555 0)
      (effects (font (size 1.27 1.27) (thickness 0.15)) (justify left bottom) hide)
    )
    (property "MPN" "ERJ2GE0R00X" (at 382.27 120.015 0)
      (effects (font (size 1.27 1.27) (thickness 0.15)) (justify left bottom) hide)
    )
    (property "Val" "0R" (at 364.49 97.79 0)
      (effects (font (size 1.27 1.27) (thickness 0.15)))
    )
    (property "License" "Apache-2.0" (at 382.27 125.095 0)
      (effects (font (size 1.27 1.27) (thickness 0.15)) (justify left bottom) hide)
    )
    (property "Author" "Antmicro" (at 382.27 127.635 0)
      (effects (font (size 1.27 1.27) (thickness 0.15)) (justify left bottom) hide)
    )
    (property "Tolerance" "~" (at 382.27 109.855 0)
      (effects (font (size 1.27 1.27)) (justify left bottom) hide)
    )
    (property "Current" "1A" (at 382.27 130.175 0)
      (effects (font (size 1.27 1.27) (thickness 0.15)) (justify left bottom) hide)
    )
    (property "DNP" "DNP" (at 364.49 99.695 0)
      (effects (font (size 1.27 1.27)))
    )
    (pin "1")
    (pin "2")
    (instances
      (project "data-center-rdimm-ddr4-tester"
        (path ""
          (reference "R196") (unit 1)
        )
      )
    )
  )

  (symbol (lib_id "antmicroResistors0402:R_10k_0402") (at 76.2 228.6 0) (unit 1)
    (in_bom yes) (on_board yes) (dnp no)
    (property "Reference" "R220" (at 78.74 223.52 0)
      (effects (font (size 1.524 1.524)))
    )
    (property "Value" "R_10k_0402" (at 96.52 241.3 0)
      (effects (font (size 1.27 1.27) (thickness 0.15)) (justify left bottom) hide)
    )
    (property "Footprint" "antmicro-footprints:R_0402_1005Metric" (at 96.52 243.84 0)
      (effects (font (size 1.27 1.27) (thickness 0.15)) (justify left bottom) hide)
    )
    (property "Datasheet" "https://www.bourns.com/docs/product-datasheets/cr.pdf" (at 96.52 246.38 0)
      (effects (font (size 1.27 1.27) (thickness 0.15)) (justify left bottom) hide)
    )
    (property "Manufacturer" "Bourns" (at 96.52 251.46 0)
      (effects (font (size 1.27 1.27) (thickness 0.15)) (justify left bottom) hide)
    )
    (property "MPN" "CR0402-FX-1002GLF" (at 96.52 248.92 0)
      (effects (font (size 1.27 1.27) (thickness 0.15)) (justify left bottom) hide)
    )
    (property "Val" "10k" (at 78.74 226.06 0)
      (effects (font (size 1.27 1.27) (thickness 0.15)))
    )
    (property "License" "Apache-2.0" (at 96.52 254 0)
      (effects (font (size 1.27 1.27) (thickness 0.15)) (justify left bottom) hide)
    )
    (property "Author" "Antmicro" (at 96.52 256.54 0)
      (effects (font (size 1.27 1.27) (thickness 0.15)) (justify left bottom) hide)
    )
    (property "Tolerance" "1%" (at 96.52 238.76 0)
      (effects (font (size 1.27 1.27)) (justify left bottom) hide)
    )
    (pin "1")
    (pin "2")
    (instances
      (project "data-center-rdimm-ddr4-tester"
        (path ""
          (reference "R220") (unit 1)
        )
      )
    )
  )

  (symbol (lib_id "antmicroCapacitors0402:C_1u_16V_0402") (at 26.035 203.2 270) (unit 1)
    (in_bom yes) (on_board yes) (dnp no) (fields_autoplaced)
    (property "Reference" "C280" (at 23.495 204.4763 90)
      (effects (font (size 1.524 1.524)) (justify right))
    )
    (property "Value" "C_1u_16V_0402" (at 15.875 223.52 0)
      (effects (font (size 1.27 1.27) (thickness 0.15)) (justify left bottom) hide)
    )
    (property "Footprint" "antmicro-footprints:C_0402_1005Metric" (at 13.335 223.52 0)
      (effects (font (size 1.27 1.27) (thickness 0.15)) (justify left bottom) hide)
    )
    (property "Datasheet" " " (at 10.795 223.52 0)
      (effects (font (size 1.27 1.27) (thickness 0.15)) (justify left bottom) hide)
    )
    (property "Manufacturer" "KEMET" (at 5.715 223.52 0)
      (effects (font (size 1.27 1.27) (thickness 0.15)) (justify left bottom) hide)
    )
    (property "MPN" "C0402C105M4PACTU" (at 8.255 223.52 0)
      (effects (font (size 1.27 1.27) (thickness 0.15)) (justify left bottom) hide)
    )
    (property "Val" "1u/16V" (at 23.495 207.6512 90)
      (effects (font (size 1.27 1.27) (thickness 0.15)) (justify right))
    )
    (property "License" "Apache-2.0" (at 3.175 223.52 0)
      (effects (font (size 1.27 1.27) (thickness 0.15)) (justify left bottom) hide)
    )
    (property "Author" "Antmicro" (at 0.635 223.52 0)
      (effects (font (size 1.27 1.27) (thickness 0.15)) (justify left bottom) hide)
    )
    (property "Voltage" "" (at -1.905 223.52 0)
      (effects (font (size 1.27 1.27)) (justify left bottom) hide)
    )
    (property "Dielectric" "" (at -4.445 223.52 0)
      (effects (font (size 1.27 1.27)) (justify left bottom) hide)
    )
    (pin "1")
    (pin "2")
    (instances
      (project "data-center-rdimm-ddr4-tester"
        (path ""
          (reference "C280") (unit 1)
        )
      )
    )
  )

  (symbol (lib_id "antmicropower:GND") (at 314.325 157.48 0) (unit 1)
    (in_bom yes) (on_board yes) (dnp no) (fields_autoplaced)
    (property "Reference" "#PWR0338" (at 314.325 163.83 0)
      (effects (font (size 1.27 1.27)) hide)
    )
    (property "Value" "GND" (at 314.325 161.925 0)
      (effects (font (size 1.27 1.27)))
    )
    (property "Footprint" "" (at 314.325 157.48 0)
      (effects (font (size 1.27 1.27)) hide)
    )
    (property "Datasheet" "" (at 314.325 157.48 0)
      (effects (font (size 1.27 1.27)) hide)
    )
    (property "Author" "Antmicro" (at 323.215 165.1 0)
      (effects (font (size 1.27 1.27) (thickness 0.15)) (justify left bottom) hide)
    )
    (property "License" "Apache-2.0" (at 323.215 167.64 0)
      (effects (font (size 1.27 1.27) (thickness 0.15)) (justify left bottom) hide)
    )
    (pin "1")
    (instances
      (project "data-center-rdimm-ddr4-tester"
        (path ""
          (reference "#PWR0338") (unit 1)
        )
      )
    )
  )

  (symbol (lib_id "antmicroTestPoints:TP_1mm_SMD") (at 156.845 230.505 180) (unit 1)
    (in_bom yes) (on_board yes) (dnp no) (fields_autoplaced)
    (property "Reference" "TP13" (at 151.765 230.5049 0)
      (effects (font (size 1.27 1.27)) (justify left))
    )
    (property "Value" "TP_1mm_SMD" (at 141.605 222.885 0)
      (effects (font (size 1.27 1.27) (thickness 0.15)) (justify left bottom) hide)
    )
    (property "Footprint" "antmicro-footprints:TP_SMD_1mm" (at 141.605 220.345 0)
      (effects (font (size 1.27 1.27) (thickness 0.15)) (justify left bottom) hide)
    )
    (property "Datasheet" "" (at 141.605 217.805 0)
      (effects (font (size 1.27 1.27) (thickness 0.15)) (justify left bottom) hide)
    )
    (property "MPN" "" (at 156.845 230.505 0)
      (effects (font (size 1.27 1.27)) hide)
    )
    (property "Manufacturer" "" (at 156.845 230.505 0)
      (effects (font (size 1.27 1.27)) hide)
    )
    (property "Author" "Antmicro" (at 141.605 215.265 0)
      (effects (font (size 1.27 1.27) (thickness 0.15)) (justify left bottom) hide)
    )
    (property "License" "Apache-2.0" (at 141.605 212.725 0)
      (effects (font (size 1.27 1.27) (thickness 0.15)) (justify left bottom) hide)
    )
    (pin "1")
    (instances
      (project "data-center-rdimm-ddr4-tester"
        (path ""
          (reference "TP13") (unit 1)
        )
      )
    )
  )

  (symbol (lib_id "antmicropower:GND") (at 389.255 42.545 0) (unit 1)
    (in_bom yes) (on_board yes) (dnp no) (fields_autoplaced)
    (property "Reference" "#PWR0352" (at 389.255 48.895 0)
      (effects (font (size 1.27 1.27)) hide)
    )
    (property "Value" "GND" (at 389.255 47.625 0)
      (effects (font (size 1.27 1.27)))
    )
    (property "Footprint" "" (at 389.255 42.545 0)
      (effects (font (size 1.27 1.27)) hide)
    )
    (property "Datasheet" "" (at 389.255 42.545 0)
      (effects (font (size 1.27 1.27)) hide)
    )
    (property "Author" "Antmicro" (at 398.145 50.165 0)
      (effects (font (size 1.27 1.27) (thickness 0.15)) (justify left bottom) hide)
    )
    (property "License" "Apache-2.0" (at 398.145 52.705 0)
      (effects (font (size 1.27 1.27) (thickness 0.15)) (justify left bottom) hide)
    )
    (pin "1")
    (instances
      (project "data-center-rdimm-ddr4-tester"
        (path ""
          (reference "#PWR0352") (unit 1)
        )
      )
    )
  )

  (symbol (lib_id "antmicroResistors0402:R_47k_0402") (at 97.155 191.135 0) (unit 1)
    (in_bom no) (on_board yes) (dnp yes)
    (property "Reference" "R117" (at 94.615 189.865 0)
      (effects (font (size 1.524 1.524)))
    )
    (property "Value" "R_47k_0402" (at 117.475 203.835 0)
      (effects (font (size 1.27 1.27) (thickness 0.15)) (justify left bottom) hide)
    )
    (property "Footprint" "antmicro-footprints:R_0402_1005Metric" (at 117.475 206.375 0)
      (effects (font (size 1.27 1.27) (thickness 0.15)) (justify left bottom) hide)
    )
    (property "Datasheet" "https://www.bourns.com/docs/product-datasheets/cr.pdf" (at 117.475 208.915 0)
      (effects (font (size 1.27 1.27) (thickness 0.15)) (justify left bottom) hide)
    )
    (property "Manufacturer" "Bourns" (at 117.475 213.995 0)
      (effects (font (size 1.27 1.27) (thickness 0.15)) (justify left bottom) hide)
    )
    (property "MPN" "CR0402-FX-4702GLF" (at 117.475 211.455 0)
      (effects (font (size 1.27 1.27) (thickness 0.15)) (justify left bottom) hide)
    )
    (property "Val" "47k" (at 103.505 189.865 0)
      (effects (font (size 1.27 1.27) (thickness 0.15)))
    )
    (property "License" "Apache-2.0" (at 117.475 216.535 0)
      (effects (font (size 1.27 1.27) (thickness 0.15)) (justify left bottom) hide)
    )
    (property "Author" "Antmicro" (at 117.475 219.075 0)
      (effects (font (size 1.27 1.27) (thickness 0.15)) (justify left bottom) hide)
    )
    (property "Tolerance" "1%" (at 117.475 201.295 0)
      (effects (font (size 1.27 1.27)) (justify left bottom) hide)
    )
    (property "DNP" "DNP" (at 99.695 191.262 0)
      (effects (font (size 1.27 1.27)))
    )
    (pin "1")
    (pin "2")
    (instances
      (project "data-center-rdimm-ddr4-tester"
        (path ""
          (reference "R117") (unit 1)
        )
      )
    )
  )

  (symbol (lib_id "antmicropower:GND") (at 45.085 255.27 0) (unit 1)
    (in_bom yes) (on_board yes) (dnp no) (fields_autoplaced)
    (property "Reference" "#PWR0371" (at 45.085 261.62 0)
      (effects (font (size 1.27 1.27)) hide)
    )
    (property "Value" "GND" (at 45.085 260.35 0)
      (effects (font (size 1.27 1.27)))
    )
    (property "Footprint" "" (at 45.085 255.27 0)
      (effects (font (size 1.27 1.27)) hide)
    )
    (property "Datasheet" "" (at 45.085 255.27 0)
      (effects (font (size 1.27 1.27)) hide)
    )
    (property "Author" "Antmicro" (at 53.975 262.89 0)
      (effects (font (size 1.27 1.27) (thickness 0.15)) (justify left bottom) hide)
    )
    (property "License" "Apache-2.0" (at 53.975 265.43 0)
      (effects (font (size 1.27 1.27) (thickness 0.15)) (justify left bottom) hide)
    )
    (pin "1")
    (instances
      (project "data-center-rdimm-ddr4-tester"
        (path ""
          (reference "#PWR0371") (unit 1)
        )
      )
    )
  )

  (symbol (lib_id "antmicropower:GND") (at 112.395 226.695 0) (unit 1)
    (in_bom yes) (on_board yes) (dnp no) (fields_autoplaced)
    (property "Reference" "#PWR0369" (at 112.395 233.045 0)
      (effects (font (size 1.27 1.27)) hide)
    )
    (property "Value" "GND" (at 112.395 231.775 0)
      (effects (font (size 1.27 1.27)))
    )
    (property "Footprint" "" (at 112.395 226.695 0)
      (effects (font (size 1.27 1.27)) hide)
    )
    (property "Datasheet" "" (at 112.395 226.695 0)
      (effects (font (size 1.27 1.27)) hide)
    )
    (property "Author" "Antmicro" (at 121.285 234.315 0)
      (effects (font (size 1.27 1.27) (thickness 0.15)) (justify left bottom) hide)
    )
    (property "License" "Apache-2.0" (at 121.285 236.855 0)
      (effects (font (size 1.27 1.27) (thickness 0.15)) (justify left bottom) hide)
    )
    (pin "1")
    (instances
      (project "data-center-rdimm-ddr4-tester"
        (path ""
          (reference "#PWR0369") (unit 1)
        )
      )
    )
  )

  (symbol (lib_id "data-center-rdimm-ddr4-tester:Net-Tie_2") (at 379.095 191.77 90) (unit 1)
    (in_bom yes) (on_board yes) (dnp no) (fields_autoplaced)
    (property "Reference" "NT8" (at 377.825 191.77 0)
      (effects (font (size 1.27 1.27)) hide)
    )
    (property "Value" "Net-Tie_2" (at 381 189.8649 90)
      (effects (font (size 1.27 1.27) (thickness 0.15)) (justify right) hide)
    )
    (property "Footprint" "data-center-rdimm-ddr4-tester-footprints:NetTie-2_SMD_Pad0.127mm" (at 384.175 170.18 0)
      (effects (font (size 1.27 1.27) (thickness 0.15)) (justify left bottom) hide)
    )
    (property "Datasheet" "" (at 386.715 170.18 0)
      (effects (font (size 1.27 1.27) (thickness 0.15)) (justify left bottom) hide)
    )
    (property "MPN" "" (at 387.985 170.18 0)
      (effects (font (size 1.27 1.27)) (justify left) hide)
    )
    (property "Manufacturer" "" (at 390.525 170.18 0)
      (effects (font (size 1.27 1.27)) (justify left) hide)
    )
    (property "Author" "Antmicro" (at 394.335 170.18 0)
      (effects (font (size 1.27 1.27) (thickness 0.15)) (justify left bottom) hide)
    )
    (property "License" "Apache-2.0" (at 396.875 170.18 0)
      (effects (font (size 1.27 1.27) (thickness 0.15)) (justify left bottom) hide)
    )
    (pin "1")
    (pin "2")
    (instances
      (project "data-center-rdimm-ddr4-tester"
        (path ""
          (reference "NT8") (unit 1)
        )
      )
    )
  )

  (symbol (lib_id "antmicropower:GND") (at 52.705 207.01 0) (unit 1)
    (in_bom yes) (on_board yes) (dnp no) (fields_autoplaced)
    (property "Reference" "#PWR0359" (at 52.705 213.36 0)
      (effects (font (size 1.27 1.27)) hide)
    )
    (property "Value" "GND" (at 52.705 212.09 0)
      (effects (font (size 1.27 1.27)))
    )
    (property "Footprint" "" (at 52.705 207.01 0)
      (effects (font (size 1.27 1.27)) hide)
    )
    (property "Datasheet" "" (at 52.705 207.01 0)
      (effects (font (size 1.27 1.27)) hide)
    )
    (property "Author" "Antmicro" (at 61.595 214.63 0)
      (effects (font (size 1.27 1.27) (thickness 0.15)) (justify left bottom) hide)
    )
    (property "License" "Apache-2.0" (at 61.595 217.17 0)
      (effects (font (size 1.27 1.27) (thickness 0.15)) (justify left bottom) hide)
    )
    (pin "1")
    (instances
      (project "data-center-rdimm-ddr4-tester"
        (path ""
          (reference "#PWR0359") (unit 1)
        )
      )
    )
  )

  (symbol (lib_id "antmicroResistors0402:R_10k_0402") (at 163.83 182.245 180) (unit 1)
    (in_bom yes) (on_board yes) (dnp no)
    (property "Reference" "R123" (at 161.29 177.165 0)
      (effects (font (size 1.524 1.524)))
    )
    (property "Value" "R_10k_0402" (at 143.51 169.545 0)
      (effects (font (size 1.27 1.27) (thickness 0.15)) (justify left bottom) hide)
    )
    (property "Footprint" "antmicro-footprints:R_0402_1005Metric" (at 143.51 167.005 0)
      (effects (font (size 1.27 1.27) (thickness 0.15)) (justify left bottom) hide)
    )
    (property "Datasheet" "https://www.bourns.com/docs/product-datasheets/cr.pdf" (at 143.51 164.465 0)
      (effects (font (size 1.27 1.27) (thickness 0.15)) (justify left bottom) hide)
    )
    (property "Manufacturer" "Bourns" (at 143.51 159.385 0)
      (effects (font (size 1.27 1.27) (thickness 0.15)) (justify left bottom) hide)
    )
    (property "MPN" "CR0402-FX-1002GLF" (at 143.51 161.925 0)
      (effects (font (size 1.27 1.27) (thickness 0.15)) (justify left bottom) hide)
    )
    (property "Val" "10k" (at 161.29 179.705 0)
      (effects (font (size 1.27 1.27) (thickness 0.15)))
    )
    (property "License" "Apache-2.0" (at 143.51 156.845 0)
      (effects (font (size 1.27 1.27) (thickness 0.15)) (justify left bottom) hide)
    )
    (property "Author" "Antmicro" (at 143.51 154.305 0)
      (effects (font (size 1.27 1.27) (thickness 0.15)) (justify left bottom) hide)
    )
    (property "Tolerance" "1%" (at 143.51 172.085 0)
      (effects (font (size 1.27 1.27)) (justify left bottom) hide)
    )
    (pin "1")
    (pin "2")
    (instances
      (project "data-center-rdimm-ddr4-tester"
        (path ""
          (reference "R123") (unit 1)
        )
      )
    )
  )

  (symbol (lib_id "antmicroResistors0603:R_330R_0.25W_0603") (at 102.87 259.715 0) (unit 1)
    (in_bom yes) (on_board yes) (dnp no)
    (property "Reference" "R29" (at 100.965 258.445 0)
      (effects (font (size 1.524 1.524)))
    )
    (property "Value" "R_330R_0.25W_0603" (at 123.19 272.415 0)
      (effects (font (size 1.27 1.27) (thickness 0.15)) (justify left bottom) hide)
    )
    (property "Footprint" "antmicro-footprints:R_0603_1608Metric" (at 123.19 274.955 0)
      (effects (font (size 1.27 1.27) (thickness 0.15)) (justify left bottom) hide)
    )
    (property "Datasheet" "https://www.mouser.pl/datasheet/2/315/Panasonic_Resistors_Thick_Film_Anti_Sulf_Anti_Surg-1825099.pdf" (at 123.19 277.495 0)
      (effects (font (size 1.27 1.27) (thickness 0.15)) (justify left bottom) hide)
    )
    (property "Manufacturer" "Panasonic" (at 123.19 282.575 0)
      (effects (font (size 1.27 1.27) (thickness 0.15)) (justify left bottom) hide)
    )
    (property "MPN" "ERJ-UP3F3300V" (at 123.19 280.035 0)
      (effects (font (size 1.27 1.27) (thickness 0.15)) (justify left bottom) hide)
    )
    (property "Val" "330R" (at 110.49 258.445 0)
      (effects (font (size 1.27 1.27) (thickness 0.15)))
    )
    (property "License" "Apache-2.0" (at 123.19 285.115 0)
      (effects (font (size 1.27 1.27) (thickness 0.15)) (justify left bottom) hide)
    )
    (property "Author" "Antmicro" (at 123.19 287.655 0)
      (effects (font (size 1.27 1.27) (thickness 0.15)) (justify left bottom) hide)
    )
    (property "Tolerance" "1%" (at 123.19 269.875 0)
      (effects (font (size 1.27 1.27)) (justify left bottom) hide)
    )
    (pin "1")
    (pin "2")
    (instances
      (project "data-center-rdimm-ddr4-tester"
        (path ""
          (reference "R29") (unit 1)
        )
      )
    )
  )

  (symbol (lib_id "antmicroResistorsmisc:R_0R01_1206") (at 381 196.85 0) (unit 1)
    (in_bom yes) (on_board yes) (dnp no)
    (property "Reference" "R203" (at 383.54 191.77 0)
      (effects (font (size 1.524 1.524)))
    )
    (property "Value" "R_0R01_1206" (at 401.32 209.55 0)
      (effects (font (size 1.27 1.27) (thickness 0.15)) (justify left bottom) hide)
    )
    (property "Footprint" "antmicro-footprints:R_1206_3216Metric" (at 401.32 212.09 0)
      (effects (font (size 1.27 1.27) (thickness 0.15)) (justify left bottom) hide)
    )
    (property "Datasheet" "https://www.yageo.com/upload/media/product/productsearch/datasheet/rchip/PYu-RL_Group_521_RoHS_L_2.pdf" (at 401.32 214.63 0)
      (effects (font (size 1.27 1.27) (thickness 0.15)) (justify left bottom) hide)
    )
    (property "Manufacturer" "Yaego" (at 401.32 219.71 0)
      (effects (font (size 1.27 1.27) (thickness 0.15)) (justify left bottom) hide)
    )
    (property "MPN" "RL1206FR-7W0R01L" (at 401.32 217.17 0)
      (effects (font (size 1.27 1.27) (thickness 0.15)) (justify left bottom) hide)
    )
    (property "Val" "0R01" (at 383.54 194.31 0)
      (effects (font (size 1.27 1.27) (thickness 0.15)))
    )
    (property "License" "Apache-2.0" (at 401.32 222.25 0)
      (effects (font (size 1.27 1.27) (thickness 0.15)) (justify left bottom) hide)
    )
    (property "Author" "Antmicro" (at 401.32 224.79 0)
      (effects (font (size 1.27 1.27) (thickness 0.15)) (justify left bottom) hide)
    )
    (property "Tolerance" "1%" (at 401.32 207.01 0)
      (effects (font (size 1.27 1.27)) (justify left bottom) hide)
    )
    (pin "1")
    (pin "2")
    (instances
      (project "data-center-rdimm-ddr4-tester"
        (path ""
          (reference "R203") (unit 1)
        )
      )
    )
  )

  (symbol (lib_id "antmicroTransistorsFETsMOSFETsSingle:BSS138PW") (at 203.073 51.435 0) (unit 1)
    (in_bom yes) (on_board yes) (dnp no) (fields_autoplaced)
    (property "Reference" "Q11" (at 213.995 47.625 0)
      (effects (font (size 1.524 1.524)) (justify left))
    )
    (property "Value" "BSS138PW" (at 213.995 50.7999 0)
      (effects (font (size 1.27 1.27) (thickness 0.15)) (justify left))
    )
    (property "Footprint" "antmicro-footprints:SC70-3" (at 225.933 62.865 0)
      (effects (font (size 1.27 1.27) (thickness 0.15)) (justify left bottom) hide)
    )
    (property "Datasheet" "https://assets.nexperia.com/documents/data-sheet/BSS138PW.pdf" (at 225.933 65.405 0)
      (effects (font (size 1.27 1.27) (thickness 0.15)) (justify left bottom) hide)
    )
    (property "MPN" "BSS138PW" (at 225.933 67.945 0)
      (effects (font (size 1.27 1.27) (thickness 0.15)) (justify left bottom) hide)
    )
    (property "Manufacturer" "Nexperia" (at 225.933 70.485 0)
      (effects (font (size 1.27 1.27) (thickness 0.15)) (justify left bottom) hide)
    )
    (property "Author" "Antmicro" (at 225.933 73.025 0)
      (effects (font (size 1.27 1.27) (thickness 0.15)) (justify left bottom) hide)
    )
    (property "License" "Apache-2.0" (at 225.933 75.565 0)
      (effects (font (size 1.27 1.27) (thickness 0.15)) (justify left bottom) hide)
    )
    (pin "1")
    (pin "2")
    (pin "3")
    (instances
      (project "data-center-rdimm-ddr4-tester"
        (path ""
          (reference "Q11") (unit 1)
        )
      )
    )
  )

  (symbol (lib_id "data-center-rdimm-ddr4-tester:Net-Tie_2") (at 379.095 132.08 90) (unit 1)
    (in_bom yes) (on_board yes) (dnp no) (fields_autoplaced)
    (property "Reference" "NT1" (at 377.825 132.08 0)
      (effects (font (size 1.27 1.27)) hide)
    )
    (property "Value" "Net-Tie_2" (at 380.365 130.1749 90)
      (effects (font (size 1.27 1.27) (thickness 0.15)) (justify right) hide)
    )
    (property "Footprint" "data-center-rdimm-ddr4-tester-footprints:NetTie-2_SMD_Pad0.127mm" (at 384.175 110.49 0)
      (effects (font (size 1.27 1.27) (thickness 0.15)) (justify left bottom) hide)
    )
    (property "Datasheet" "" (at 386.715 110.49 0)
      (effects (font (size 1.27 1.27) (thickness 0.15)) (justify left bottom) hide)
    )
    (property "MPN" "" (at 387.985 110.49 0)
      (effects (font (size 1.27 1.27)) (justify left) hide)
    )
    (property "Manufacturer" "" (at 390.525 110.49 0)
      (effects (font (size 1.27 1.27)) (justify left) hide)
    )
    (property "Author" "Antmicro" (at 394.335 110.49 0)
      (effects (font (size 1.27 1.27) (thickness 0.15)) (justify left bottom) hide)
    )
    (property "License" "Apache-2.0" (at 396.875 110.49 0)
      (effects (font (size 1.27 1.27) (thickness 0.15)) (justify left bottom) hide)
    )
    (pin "1")
    (pin "2")
    (instances
      (project "data-center-rdimm-ddr4-tester"
        (path ""
          (reference "NT1") (unit 1)
        )
      )
    )
  )

  (symbol (lib_id "antmicroCapacitors0402:C_100n_0402") (at 165.1 28.575 270) (unit 1)
    (in_bom yes) (on_board yes) (dnp no)
    (property "Reference" "C30" (at 165.735 29.21 90)
      (effects (font (size 1.524 1.524)) (justify left))
    )
    (property "Value" "C_100n_0402" (at 154.94 48.895 0)
      (effects (font (size 1.27 1.27) (thickness 0.15)) (justify left bottom) hide)
    )
    (property "Footprint" "antmicro-footprints:C_0402_1005Metric" (at 152.4 48.895 0)
      (effects (font (size 1.27 1.27) (thickness 0.15)) (justify left bottom) hide)
    )
    (property "Datasheet" "https://search.murata.co.jp/Ceramy/image/img/A01X/G101/ENG/GRM155R61H104KE14-01.pdf" (at 149.86 48.895 0)
      (effects (font (size 1.27 1.27) (thickness 0.15)) (justify left bottom) hide)
    )
    (property "Manufacturer" "Murata" (at 144.78 48.895 0)
      (effects (font (size 1.27 1.27) (thickness 0.15)) (justify left bottom) hide)
    )
    (property "MPN" "GRM155R61H104KE14D" (at 147.32 48.895 0)
      (effects (font (size 1.27 1.27) (thickness 0.15)) (justify left bottom) hide)
    )
    (property "Val" "100n" (at 165.735 33.02 90)
      (effects (font (size 1.27 1.27) (thickness 0.15)) (justify left))
    )
    (property "License" "Apache-2.0" (at 142.24 48.895 0)
      (effects (font (size 1.27 1.27) (thickness 0.15)) (justify left bottom) hide)
    )
    (property "Author" "Antmicro" (at 139.7 48.895 0)
      (effects (font (size 1.27 1.27) (thickness 0.15)) (justify left bottom) hide)
    )
    (property "Voltage" "50V" (at 137.16 48.895 0)
      (effects (font (size 1.27 1.27)) (justify left bottom) hide)
    )
    (property "Dielectric" "X5R" (at 134.62 48.895 0)
      (effects (font (size 1.27 1.27)) (justify left bottom) hide)
    )
    (pin "1")
    (pin "2")
    (instances
      (project "data-center-rdimm-ddr4-tester"
        (path ""
          (reference "C30") (unit 1)
        )
      )
    )
  )

  (symbol (lib_id "antmicroResistors0402:R_100k_0402") (at 201.803 57.785 90) (unit 1)
    (in_bom yes) (on_board yes) (dnp no)
    (property "Reference" "R124" (at 203.073 54.61 90)
      (effects (font (size 1.524 1.524)) (justify right))
    )
    (property "Value" "R_100k_0402" (at 214.503 37.465 0)
      (effects (font (size 1.27 1.27) (thickness 0.15)) (justify left bottom) hide)
    )
    (property "Footprint" "antmicro-footprints:R_0402_1005Metric" (at 217.043 37.465 0)
      (effects (font (size 1.27 1.27) (thickness 0.15)) (justify left bottom) hide)
    )
    (property "Datasheet" "https://www.bourns.com/docs/product-datasheets/cr.pdf" (at 219.583 37.465 0)
      (effects (font (size 1.27 1.27) (thickness 0.15)) (justify left bottom) hide)
    )
    (property "Manufacturer" "Bourns" (at 224.663 37.465 0)
      (effects (font (size 1.27 1.27) (thickness 0.15)) (justify left bottom) hide)
    )
    (property "MPN" "CR0402-FX-1003GLF" (at 222.123 37.465 0)
      (effects (font (size 1.27 1.27) (thickness 0.15)) (justify left bottom) hide)
    )
    (property "Val" "100k" (at 203.708 56.515 90)
      (effects (font (size 1.27 1.27) (thickness 0.15)) (justify right))
    )
    (property "License" "Apache-2.0" (at 227.203 37.465 0)
      (effects (font (size 1.27 1.27) (thickness 0.15)) (justify left bottom) hide)
    )
    (property "Author" "Antmicro" (at 229.743 37.465 0)
      (effects (font (size 1.27 1.27) (thickness 0.15)) (justify left bottom) hide)
    )
    (property "Tolerance" "1%" (at 211.963 37.465 0)
      (effects (font (size 1.27 1.27)) (justify left bottom) hide)
    )
    (pin "1")
    (pin "2")
    (instances
      (project "data-center-rdimm-ddr4-tester"
        (path ""
          (reference "R124") (unit 1)
        )
      )
    )
  )

  (symbol (lib_id "antmicropower:GND") (at 201.803 57.785 0) (unit 1)
    (in_bom yes) (on_board yes) (dnp no) (fields_autoplaced)
    (property "Reference" "#PWR0372" (at 201.803 64.135 0)
      (effects (font (size 1.27 1.27)) hide)
    )
    (property "Value" "GND" (at 201.803 62.865 0)
      (effects (font (size 1.27 1.27)))
    )
    (property "Footprint" "" (at 201.803 57.785 0)
      (effects (font (size 1.27 1.27)) hide)
    )
    (property "Datasheet" "" (at 201.803 57.785 0)
      (effects (font (size 1.27 1.27)) hide)
    )
    (property "Author" "Antmicro" (at 210.693 65.405 0)
      (effects (font (size 1.27 1.27) (thickness 0.15)) (justify left bottom) hide)
    )
    (property "License" "Apache-2.0" (at 210.693 67.945 0)
      (effects (font (size 1.27 1.27) (thickness 0.15)) (justify left bottom) hide)
    )
    (pin "1")
    (instances
      (project "data-center-rdimm-ddr4-tester"
        (path ""
          (reference "#PWR0372") (unit 1)
        )
      )
    )
  )

  (symbol (lib_id "antmicroCapacitors0402:C_100n_0402") (at 394.335 52.07 270) (unit 1)
    (in_bom yes) (on_board yes) (dnp no) (fields_autoplaced)
    (property "Reference" "C237" (at 397.51 53.3463 90)
      (effects (font (size 1.524 1.524)) (justify left))
    )
    (property "Value" "C_100n_0402" (at 384.175 72.39 0)
      (effects (font (size 1.27 1.27) (thickness 0.15)) (justify left bottom) hide)
    )
    (property "Footprint" "antmicro-footprints:C_0402_1005Metric" (at 381.635 72.39 0)
      (effects (font (size 1.27 1.27) (thickness 0.15)) (justify left bottom) hide)
    )
    (property "Datasheet" "https://search.murata.co.jp/Ceramy/image/img/A01X/G101/ENG/GRM155R61H104KE14-01.pdf" (at 379.095 72.39 0)
      (effects (font (size 1.27 1.27) (thickness 0.15)) (justify left bottom) hide)
    )
    (property "Manufacturer" "Murata" (at 374.015 72.39 0)
      (effects (font (size 1.27 1.27) (thickness 0.15)) (justify left bottom) hide)
    )
    (property "MPN" "GRM155R61H104KE14D" (at 376.555 72.39 0)
      (effects (font (size 1.27 1.27) (thickness 0.15)) (justify left bottom) hide)
    )
    (property "Val" "100n" (at 397.51 56.5212 90)
      (effects (font (size 1.27 1.27) (thickness 0.15)) (justify left))
    )
    (property "License" "Apache-2.0" (at 371.475 72.39 0)
      (effects (font (size 1.27 1.27) (thickness 0.15)) (justify left bottom) hide)
    )
    (property "Author" "Antmicro" (at 368.935 72.39 0)
      (effects (font (size 1.27 1.27) (thickness 0.15)) (justify left bottom) hide)
    )
    (property "Voltage" "50V" (at 366.395 72.39 0)
      (effects (font (size 1.27 1.27)) (justify left bottom) hide)
    )
    (property "Dielectric" "X5R" (at 363.855 72.39 0)
      (effects (font (size 1.27 1.27)) (justify left bottom) hide)
    )
    (pin "1")
    (pin "2")
    (instances
      (project "data-center-rdimm-ddr4-tester"
        (path ""
          (reference "C237") (unit 1)
        )
      )
    )
  )

  (symbol (lib_id "antmicropower:GND") (at 394.335 57.15 0) (unit 1)
    (in_bom yes) (on_board yes) (dnp no) (fields_autoplaced)
    (property "Reference" "#PWR0328" (at 394.335 63.5 0)
      (effects (font (size 1.27 1.27)) hide)
    )
    (property "Value" "GND" (at 394.335 61.595 0)
      (effects (font (size 1.27 1.27)))
    )
    (property "Footprint" "" (at 394.335 57.15 0)
      (effects (font (size 1.27 1.27)) hide)
    )
    (property "Datasheet" "" (at 394.335 57.15 0)
      (effects (font (size 1.27 1.27)) hide)
    )
    (property "Author" "Antmicro" (at 403.225 64.77 0)
      (effects (font (size 1.27 1.27) (thickness 0.15)) (justify left bottom) hide)
    )
    (property "License" "Apache-2.0" (at 403.225 67.31 0)
      (effects (font (size 1.27 1.27) (thickness 0.15)) (justify left bottom) hide)
    )
    (pin "1")
    (instances
      (project "data-center-rdimm-ddr4-tester"
        (path ""
          (reference "#PWR0328") (unit 1)
        )
      )
    )
  )

  (symbol (lib_id "data-center-rdimm-ddr4-tester:Net-Tie_2") (at 387.985 191.77 90) (unit 1)
    (in_bom yes) (on_board yes) (dnp no) (fields_autoplaced)
    (property "Reference" "NT12" (at 386.715 191.77 0)
      (effects (font (size 1.27 1.27)) hide)
    )
    (property "Value" "Net-Tie_2" (at 389.89 189.8649 90)
      (effects (font (size 1.27 1.27) (thickness 0.15)) (justify right) hide)
    )
    (property "Footprint" "data-center-rdimm-ddr4-tester-footprints:NetTie-2_SMD_Pad0.127mm" (at 393.065 170.18 0)
      (effects (font (size 1.27 1.27) (thickness 0.15)) (justify left bottom) hide)
    )
    (property "Datasheet" "" (at 395.605 170.18 0)
      (effects (font (size 1.27 1.27) (thickness 0.15)) (justify left bottom) hide)
    )
    (property "MPN" "" (at 396.875 170.18 0)
      (effects (font (size 1.27 1.27)) (justify left) hide)
    )
    (property "Manufacturer" "" (at 399.415 170.18 0)
      (effects (font (size 1.27 1.27)) (justify left) hide)
    )
    (property "Author" "Antmicro" (at 403.225 170.18 0)
      (effects (font (size 1.27 1.27) (thickness 0.15)) (justify left bottom) hide)
    )
    (property "License" "Apache-2.0" (at 405.765 170.18 0)
      (effects (font (size 1.27 1.27) (thickness 0.15)) (justify left bottom) hide)
    )
    (pin "1")
    (pin "2")
    (instances
      (project "data-center-rdimm-ddr4-tester"
        (path ""
          (reference "NT12") (unit 1)
        )
      )
    )
  )

  (symbol (lib_id "data-center-rdimm-ddr4-tester:Net-Tie_2") (at 387.985 151.13 90) (unit 1)
    (in_bom yes) (on_board yes) (dnp no) (fields_autoplaced)
    (property "Reference" "NT6" (at 386.715 151.13 0)
      (effects (font (size 1.27 1.27)) hide)
    )
    (property "Value" "Net-Tie_2" (at 389.255 149.2249 90)
      (effects (font (size 1.27 1.27) (thickness 0.15)) (justify right) hide)
    )
    (property "Footprint" "data-center-rdimm-ddr4-tester-footprints:NetTie-2_SMD_Pad0.127mm" (at 393.065 129.54 0)
      (effects (font (size 1.27 1.27) (thickness 0.15)) (justify left bottom) hide)
    )
    (property "Datasheet" "" (at 395.605 129.54 0)
      (effects (font (size 1.27 1.27) (thickness 0.15)) (justify left bottom) hide)
    )
    (property "MPN" "" (at 396.875 129.54 0)
      (effects (font (size 1.27 1.27)) (justify left) hide)
    )
    (property "Manufacturer" "" (at 399.415 129.54 0)
      (effects (font (size 1.27 1.27)) (justify left) hide)
    )
    (property "Author" "Antmicro" (at 403.225 129.54 0)
      (effects (font (size 1.27 1.27) (thickness 0.15)) (justify left bottom) hide)
    )
    (property "License" "Apache-2.0" (at 405.765 129.54 0)
      (effects (font (size 1.27 1.27) (thickness 0.15)) (justify left bottom) hide)
    )
    (pin "1")
    (pin "2")
    (instances
      (project "data-center-rdimm-ddr4-tester"
        (path ""
          (reference "NT6") (unit 1)
        )
      )
    )
  )

  (symbol (lib_id "antmicroResistorsmisc:R_0R01_1206") (at 381 177.8 0) (unit 1)
    (in_bom yes) (on_board yes) (dnp no)
    (property "Reference" "R201" (at 383.54 172.72 0)
      (effects (font (size 1.524 1.524)))
    )
    (property "Value" "R_0R01_1206" (at 401.32 190.5 0)
      (effects (font (size 1.27 1.27) (thickness 0.15)) (justify left bottom) hide)
    )
    (property "Footprint" "antmicro-footprints:R_1206_3216Metric" (at 401.32 193.04 0)
      (effects (font (size 1.27 1.27) (thickness 0.15)) (justify left bottom) hide)
    )
    (property "Datasheet" "https://www.yageo.com/upload/media/product/productsearch/datasheet/rchip/PYu-RL_Group_521_RoHS_L_2.pdf" (at 401.32 195.58 0)
      (effects (font (size 1.27 1.27) (thickness 0.15)) (justify left bottom) hide)
    )
    (property "Manufacturer" "Yaego" (at 401.32 200.66 0)
      (effects (font (size 1.27 1.27) (thickness 0.15)) (justify left bottom) hide)
    )
    (property "MPN" "RL1206FR-7W0R01L" (at 401.32 198.12 0)
      (effects (font (size 1.27 1.27) (thickness 0.15)) (justify left bottom) hide)
    )
    (property "Val" "0R01" (at 383.54 175.26 0)
      (effects (font (size 1.27 1.27) (thickness 0.15)))
    )
    (property "License" "Apache-2.0" (at 401.32 203.2 0)
      (effects (font (size 1.27 1.27) (thickness 0.15)) (justify left bottom) hide)
    )
    (property "Author" "Antmicro" (at 401.32 205.74 0)
      (effects (font (size 1.27 1.27) (thickness 0.15)) (justify left bottom) hide)
    )
    (property "Tolerance" "1%" (at 401.32 187.96 0)
      (effects (font (size 1.27 1.27)) (justify left bottom) hide)
    )
    (pin "1")
    (pin "2")
    (instances
      (project "data-center-rdimm-ddr4-tester"
        (path ""
          (reference "R201") (unit 1)
        )
      )
    )
  )
)
